FILE_TYPE = MACRO_DRAWING;
SET COLOR_WIRE YELLOW;
SET COLOR_PROP ORANGE;
SET COLOR_DOT WHITE;
SET COLOR_ARC YELLOW;
SET COLOR_BODY GREEN;
SET COLOR_NOTE PURPLE;
SET PROP_DISPLAY VALUE;
SET PAGE_NUMBER P475;
FORCEADD UNIVERSAL_GND..1
(-8900 2675);
FORCEPROP 3 LASTPIN (-8900 2725) SIG_NAME GND\g
J 0
(-8890 2735);
DISPLAY 0.659574 (-8890 2735);
PAINT MONO (-8890 2735);
DISPLAY INVISIBLE (-8890 2735);
FORCEPROP 2 LAST CDS_LIB pure_quanta_power
J 0
(-8900 2675);
PAINT MONO (-8900 2675);
DISPLAY INVISIBLE (-8900 2675);
FORCEPROP 1 LAST HDL_POWER GND
J 1
(-8875 2600);
DISPLAY 0.872340 (-8875 2600);
PAINT GREEN (-8875 2600);
DISPLAY INVISIBLE (-8875 2600);
FORCEPROP 1 LAST PATH I10
J 0
(-8825 2675);
DISPLAY 0.872340 (-8825 2675);
PAINT AQUA (-8825 2675);
DISPLAY INVISIBLE (-8825 2675);
FORCEADD Q_RES..1
(-8900 5875);
FORCEPROP 1 LAST LOCATION PR6531
J 0
(-9150 5875);
DISPLAY 0.787234 (-9150 5875);
FORCEPROP 2 LAST SEC 1
J 0
(-8950 6075);
DISPLAY 0.680851 (-8950 6075);
PAINT MONO (-8950 6075);
DISPLAY INVISIBLE (-8950 6075);
FORCEPROP 1 LASTPIN (-9000 5875) $PN 1
J 0
(-8988 5887);
DISPLAY 0.787234 (-8988 5887);
PAINT MONO (-8988 5887);
FORCEPROP 1 LASTPIN (-8800 5875) $PN 2
J 0
(-8838 5887);
DISPLAY 0.787234 (-8838 5887);
PAINT MONO (-8838 5887);
FORCEPROP 1 LAST TOLERANCE 5%
J 0
(-8875 5800);
DISPLAY 0.510638 (-8875 5800);
FORCEPROP 1 LAST VALUE 0
J 2
(-8925 5800);
DISPLAY 0.510638 (-8925 5800);
FORCEPROP 1 LAST PACK_TYPE 0402LF
J 0
(-8750 6000);
DISPLAY 0.510638 (-8750 6000);
DISPLAY INVISIBLE (-8750 6000);
FORCEPROP 1 LAST WATTAGE 1/16W
J 2
(-8775 6000);
DISPLAY 0.510638 (-8775 6000);
DISPLAY INVISIBLE (-8775 6000);
FORCEPROP 1 LAST MATERIAL CHIP
J 0
(-9025 6000);
DISPLAY 0.510638 (-9025 6000);
DISPLAY INVISIBLE (-9025 6000);
FORCEPROP 2 LAST SEC_TYPE 0402LF
J 0
(-8950 6075);
DISPLAY 1.021277 (-8950 6075);
DISPLAY INVISIBLE (-8950 6075);
FORCEPROP 2 LAST CDS_LIB pure_quanta
J 0
(-8900 5875);
DISPLAY INVISIBLE (-8900 5875);
FORCEPROP 1 LAST PATH I105
J 0
(-8950 6025);
DISPLAY 0.978723 (-8950 6025);
PAINT WHITE (-8950 6025);
DISPLAY INVISIBLE (-8950 6025);
FORCEPROP 1 LAST PART_NUMBER CS00002JB13
J 0
(-9025 5950);
DISPLAY 0.510638 (-9025 5950);
DISPLAY INVISIBLE (-9025 5950);
FORCEADD Q_CAP..2
(-8450 8025);
FORCEPROP 1 LAST LOCATION C101
J 1
(-8625 8025);
DISPLAY 0.638298 (-8625 8025);
FORCEPROP 2 LAST SEC 1
J 0
(-8450 8275);
DISPLAY 0.680851 (-8450 8275);
PAINT MONO (-8450 8275);
DISPLAY INVISIBLE (-8450 8275);
FORCEPROP 1 LASTPIN (-8550 8025) $PN 1
J 0
(-8560 8040);
DISPLAY 0.787234 (-8560 8040);
PAINT MONO (-8560 8040);
FORCEPROP 1 LASTPIN (-8350 8025) $PN 2
J 0
(-8365 8040);
DISPLAY 0.787234 (-8365 8040);
PAINT MONO (-8365 8040);
FORCEPROP 1 LAST TOLERANCE 5%
J 2
(-8050 8025);
DISPLAY 0.510638 (-8050 8025);
FORCEPROP 1 LAST MATERIAL EMPTY
J 0
(-8575 8175);
DISPLAY 0.510638 (-8575 8175);
FORCEPROP 1 LAST VALUE 1000PF
J 2
(-8125 8025);
DISPLAY 0.510638 (-8125 8025);
FORCEPROP 1 LAST VOLTAGE 50V
J 0
(-8425 8175);
DISPLAY 0.510638 (-8425 8175);
FORCEPROP 1 LAST PACK_TYPE 0402
J 1
(-8250 8175);
DISPLAY 0.510638 (-8250 8175);
FORCEPROP 2 LAST SEC_TYPE 0402
J 0
(-8450 8275);
DISPLAY 1.021277 (-8450 8275);
DISPLAY INVISIBLE (-8450 8275);
FORCEPROP 2 LAST CDS_LIB pure_quanta
J 0
(-8450 8025);
DISPLAY INVISIBLE (-8450 8025);
FORCEPROP 1 LAST PATH I118
J 0
(-8450 8225);
DISPLAY 0.978723 (-8450 8225);
PAINT WHITE (-8450 8225);
DISPLAY INVISIBLE (-8450 8225);
FORCEPROP 1 LAST PART_NUMBER TMP_QCH21006JB10
J 1
(-8400 8125);
DISPLAY 0.510638 (-8400 8125);
DISPLAY INVISIBLE (-8400 8125);
FORCEADD Q_RES..1
(-9950 7875);
FORCEPROP 1 LAST LOCATION R650
J 0
(-10225 7875);
DISPLAY 0.638298 (-10225 7875);
FORCEPROP 2 LAST SEC 1
J 0
(-10000 8075);
DISPLAY 0.680851 (-10000 8075);
PAINT MONO (-10000 8075);
DISPLAY INVISIBLE (-10000 8075);
FORCEPROP 1 LASTPIN (-10050 7875) $PN 1
J 0
(-10038 7887);
DISPLAY 0.787234 (-10038 7887);
PAINT MONO (-10038 7887);
FORCEPROP 1 LASTPIN (-9850 7875) $PN 2
J 0
(-9888 7887);
DISPLAY 0.787234 (-9888 7887);
PAINT MONO (-9888 7887);
FORCEPROP 1 LAST VALUE 0
J 2
(-9725 7875);
DISPLAY 0.510638 (-9725 7875);
FORCEPROP 1 LAST TOLERANCE 5%
J 0
(-9675 7875);
DISPLAY 0.510638 (-9675 7875);
FORCEPROP 1 LAST PACK_TYPE 0402LF
J 0
(-9800 7975);
DISPLAY 0.510638 (-9800 7975);
FORCEPROP 1 LAST MATERIAL CHIP
J 0
(-10075 7975);
DISPLAY 0.510638 (-10075 7975);
FORCEPROP 1 LAST WATTAGE 1/16W
J 2
(-9825 7975);
DISPLAY 0.510638 (-9825 7975);
FORCEPROP 2 LAST SEC_TYPE 0402LF
J 0
(-10000 8075);
DISPLAY 1.021277 (-10000 8075);
DISPLAY INVISIBLE (-10000 8075);
FORCEPROP 2 LAST CDS_LIB pure_quanta
J 0
(-9950 7875);
DISPLAY INVISIBLE (-9950 7875);
FORCEPROP 1 LAST PATH I119
J 0
(-10000 8025);
DISPLAY 0.978723 (-10000 8025);
PAINT WHITE (-10000 8025);
DISPLAY INVISIBLE (-10000 8025);
FORCEPROP 1 LAST PART_NUMBER CS00002JB13
J 0
(-10075 7925);
DISPLAY 0.510638 (-10075 7925);
DISPLAY INVISIBLE (-10075 7925);
FORCEADD Q_RES..1
(-9300 7725);
FORCEPROP 1 LAST LOCATION R651
J 0
(-9575 7725);
DISPLAY 0.638298 (-9575 7725);
FORCEPROP 2 LAST SEC 1
J 0
(-9350 7925);
DISPLAY 0.680851 (-9350 7925);
PAINT MONO (-9350 7925);
DISPLAY INVISIBLE (-9350 7925);
FORCEPROP 1 LASTPIN (-9400 7725) $PN 1
J 0
(-9388 7737);
DISPLAY 0.787234 (-9388 7737);
PAINT MONO (-9388 7737);
FORCEPROP 1 LASTPIN (-9200 7725) $PN 2
J 0
(-9238 7737);
DISPLAY 0.787234 (-9238 7737);
PAINT MONO (-9238 7737);
FORCEPROP 1 LAST TOLERANCE 5%
J 0
(-9025 7725);
DISPLAY 0.510638 (-9025 7725);
FORCEPROP 1 LAST VALUE 0
J 2
(-9075 7725);
DISPLAY 0.510638 (-9075 7725);
FORCEPROP 1 LAST PACK_TYPE 0402LF
J 0
(-9150 7850);
DISPLAY 0.510638 (-9150 7850);
DISPLAY INVISIBLE (-9150 7850);
FORCEPROP 1 LAST MATERIAL CHIP
J 0
(-9425 7850);
DISPLAY 0.510638 (-9425 7850);
DISPLAY INVISIBLE (-9425 7850);
FORCEPROP 1 LAST WATTAGE 1/16W
J 2
(-9175 7850);
DISPLAY 0.510638 (-9175 7850);
DISPLAY INVISIBLE (-9175 7850);
FORCEPROP 2 LAST SEC_TYPE 0402LF
J 0
(-9350 7925);
DISPLAY 1.021277 (-9350 7925);
DISPLAY INVISIBLE (-9350 7925);
FORCEPROP 2 LAST CDS_LIB pure_quanta
J 0
(-9300 7725);
DISPLAY INVISIBLE (-9300 7725);
FORCEPROP 1 LAST PATH I120
J 0
(-9350 7875);
DISPLAY 0.978723 (-9350 7875);
PAINT WHITE (-9350 7875);
DISPLAY INVISIBLE (-9350 7875);
FORCEPROP 1 LAST PART_NUMBER CS00002JB13
J 0
(-9425 7800);
DISPLAY 0.510638 (-9425 7800);
DISPLAY INVISIBLE (-9425 7800);
FORCEADD Q_CAP..1
(-8450 5700);
FORCEPROP 1 LAST LOCATION PC6540
J 0
(-8400 5800);
DISPLAY 0.808511 (-8400 5800);
FORCEPROP 2 LAST SEC 1
J 0
(-8400 5900);
DISPLAY 0.680851 (-8400 5900);
PAINT MONO (-8400 5900);
DISPLAY INVISIBLE (-8400 5900);
FORCEPROP 1 LASTPIN (-8450 5800) $PN 1
J 0
(-8440 5780);
DISPLAY 0.787234 (-8440 5780);
PAINT MONO (-8440 5780);
FORCEPROP 1 LASTPIN (-8450 5600) $PN 2
J 0
(-8440 5580);
DISPLAY 0.787234 (-8440 5580);
PAINT MONO (-8440 5580);
FORCEPROP 1 LAST VALUE 3300PF
J 0
(-8400 5750);
DISPLAY 0.510638 (-8400 5750);
FORCEPROP 1 LAST MATERIAL X7R
J 0
(-8400 5600);
DISPLAY 0.510638 (-8400 5600);
FORCEPROP 1 LAST PACK_TYPE 0402
J 0
(-8400 5500);
DISPLAY 0.510638 (-8400 5500);
FORCEPROP 1 LAST VOLTAGE 50V
J 0
(-8400 5700);
DISPLAY 0.510638 (-8400 5700);
FORCEPROP 1 LAST TOLERANCE 10%
J 0
(-8400 5650);
DISPLAY 0.510638 (-8400 5650);
FORCEPROP 2 LAST SEC_TYPE 0402
J 0
(-8400 5900);
DISPLAY 1.021277 (-8400 5900);
DISPLAY INVISIBLE (-8400 5900);
FORCEPROP 2 LAST CDS_LIB pure_quanta
J 0
(-8450 5700);
DISPLAY INVISIBLE (-8450 5700);
FORCEPROP 1 LAST PATH I121
J 0
(-8400 5850);
DISPLAY 0.978723 (-8400 5850);
PAINT WHITE (-8400 5850);
DISPLAY INVISIBLE (-8400 5850);
FORCEPROP 1 LAST PART_NUMBER TMP_QCH2336K1B12
J 0
(-8400 5550);
DISPLAY 0.510638 (-8400 5550);
DISPLAY INVISIBLE (-8400 5550);
FORCEADD Q_CAP..1
(-7925 2100);
FORCEPROP 1 LAST LOCATION PC6602
J 0
(-7900 2225);
DISPLAY 0.787234 (-7900 2225);
FORCEPROP 2 LAST SEC 1
J 0
(-7875 2300);
DISPLAY 0.680851 (-7875 2300);
PAINT MONO (-7875 2300);
DISPLAY INVISIBLE (-7875 2300);
FORCEPROP 1 LASTPIN (-7925 2200) $PN 1
J 0
(-7915 2180);
DISPLAY 0.787234 (-7915 2180);
PAINT MONO (-7915 2180);
FORCEPROP 1 LASTPIN (-7925 2000) $PN 2
J 0
(-7915 1980);
DISPLAY 0.787234 (-7915 1980);
PAINT MONO (-7915 1980);
FORCEPROP 1 LAST MATERIAL X7R
J 0
(-7875 2000);
DISPLAY 0.510638 (-7875 2000);
FORCEPROP 1 LAST TOLERANCE 10%
J 0
(-7875 2050);
DISPLAY 0.510638 (-7875 2050);
FORCEPROP 1 LAST VALUE 0.1UF
J 0
(-7875 2150);
DISPLAY 0.510638 (-7875 2150);
FORCEPROP 1 LAST PACK_TYPE 0402
J 0
(-7875 1900);
DISPLAY 0.510638 (-7875 1900);
FORCEPROP 1 LAST VOLTAGE 25V
J 0
(-7875 2100);
DISPLAY 0.510638 (-7875 2100);
FORCEPROP 2 LAST SEC_TYPE 0402
J 0
(-7875 2300);
DISPLAY 1.021277 (-7875 2300);
DISPLAY INVISIBLE (-7875 2300);
FORCEPROP 2 LAST CDS_LIB pure_quanta
J 0
(-7925 2100);
DISPLAY INVISIBLE (-7925 2100);
FORCEPROP 1 LAST PATH I123
J 0
(-7875 2250);
DISPLAY 0.978723 (-7875 2250);
PAINT WHITE (-7875 2250);
DISPLAY INVISIBLE (-7875 2250);
FORCEPROP 1 LAST PART_NUMBER CH4104K1B00
J 0
(-7875 1950);
DISPLAY 0.510638 (-7875 1950);
DISPLAY INVISIBLE (-7875 1950);
FORCEADD Q_RES..2
R 2
(-8050 2100);
FORCEPROP 1 LAST LOCATION PR6607
J 2
(-8095 2225);
DISPLAY 0.808511 (-8095 2225);
FORCEPROP 0 LAST $SEC 1
J 0
(-8075 2275);
DISPLAY 0.680851 (-8075 2275);
PAINT MONO (-8075 2275);
DISPLAY INVISIBLE (-8075 2275);
FORCEPROP 0 LAST CDS_SEC 1
J 0
(-8075 2275);
DISPLAY 1.021277 (-8075 2275);
DISPLAY INVISIBLE (-8075 2275);
FORCEPROP 1 LASTPIN (-8050 2200) $PN 1
J 2
(-8055 2162);
DISPLAY 0.787234 (-8055 2162);
PAINT MONO (-8055 2162);
FORCEPROP 1 LASTPIN (-8050 2000) $PN 2
J 2
(-8055 2010);
DISPLAY 0.787234 (-8055 2010);
PAINT MONO (-8055 2010);
FORCEPROP 1 LAST MATERIAL EMPTY
J 2
(-8090 2025);
DISPLAY 0.510638 (-8090 2025);
FORCEPROP 1 LAST PACK_TYPE 0402LF
J 2
(-8090 1925);
DISPLAY 0.510638 (-8090 1925);
FORCEPROP 1 LAST WATTAGE 1/16W
J 2
(-8090 2075);
DISPLAY 0.510638 (-8090 2075);
FORCEPROP 1 LAST TOLERANCE 1%
J 2
(-8095 2125);
DISPLAY 0.510638 (-8095 2125);
FORCEPROP 1 LAST VALUE 1K
J 2
(-8095 2175);
DISPLAY 0.510638 (-8095 2175);
FORCEPROP 2 LAST CDS_LIB pure_quanta
J 2
(-8050 2100);
DISPLAY INVISIBLE (-8050 2100);
FORCEPROP 1 LAST PATH I125
J 2
(-8100 2275);
DISPLAY 0.978723 (-8100 2275);
PAINT WHITE (-8100 2275);
DISPLAY INVISIBLE (-8100 2275);
FORCEPROP 1 LAST PART_NUMBER CS21002FB06
J 2
(-8090 1975);
DISPLAY 0.510638 (-8090 1975);
DISPLAY INVISIBLE (-8090 1975);
FORCEADD Q_RES..2
R 2
(-9100 4075);
FORCEPROP 1 LAST LOCATION R655
J 2
(-9155 4175);
DISPLAY 0.808511 (-9155 4175);
FORCEPROP 2 LAST SEC 1
J 2
(-9150 4300);
DISPLAY 0.680851 (-9150 4300);
PAINT MONO (-9150 4300);
DISPLAY INVISIBLE (-9150 4300);
FORCEPROP 1 LASTPIN (-9100 4175) $PN 1
J 2
(-9105 4137);
DISPLAY 0.787234 (-9105 4137);
PAINT MONO (-9105 4137);
FORCEPROP 1 LASTPIN (-9100 3975) $PN 2
J 2
(-9105 3985);
DISPLAY 0.787234 (-9105 3985);
PAINT MONO (-9105 3985);
FORCEPROP 1 LAST VALUE 1K
J 2
(-9155 4125);
DISPLAY 0.510638 (-9155 4125);
FORCEPROP 1 LAST TOLERANCE 1%
J 2
(-9155 4075);
DISPLAY 0.510638 (-9155 4075);
FORCEPROP 1 LAST WATTAGE 1/16W
J 2
(-9150 4025);
DISPLAY 0.510638 (-9150 4025);
FORCEPROP 1 LAST PACK_TYPE 0402LF
J 2
(-9150 3875);
DISPLAY 0.510638 (-9150 3875);
FORCEPROP 1 LAST MATERIAL CHIP
J 2
(-9150 3975);
DISPLAY 0.510638 (-9150 3975);
FORCEPROP 2 LAST SEC_TYPE 0402LF
J 2
(-9150 4300);
DISPLAY 1.021277 (-9150 4300);
DISPLAY INVISIBLE (-9150 4300);
FORCEPROP 2 LAST CDS_LIB pure_quanta
J 2
(-9100 4075);
DISPLAY INVISIBLE (-9100 4075);
FORCEPROP 1 LAST PATH I127
J 2
(-9150 4250);
DISPLAY 0.978723 (-9150 4250);
PAINT WHITE (-9150 4250);
DISPLAY INVISIBLE (-9150 4250);
FORCEPROP 1 LAST PART_NUMBER CS21002FB06
J 2
(-9150 3925);
DISPLAY 0.510638 (-9150 3925);
DISPLAY INVISIBLE (-9150 3925);
FORCEADD Q_RES..2
R 2
(-8725 4075);
FORCEPROP 1 LAST LOCATION R652
J 2
(-8780 4175);
DISPLAY 0.808511 (-8780 4175);
FORCEPROP 2 LAST SEC 1
J 0
(-8775 4300);
DISPLAY 0.680851 (-8775 4300);
PAINT MONO (-8775 4300);
DISPLAY INVISIBLE (-8775 4300);
FORCEPROP 1 LASTPIN (-8725 4175) $PN 1
J 2
(-8730 4137);
DISPLAY 0.787234 (-8730 4137);
PAINT MONO (-8730 4137);
FORCEPROP 1 LASTPIN (-8725 3975) $PN 2
J 2
(-8730 3985);
DISPLAY 0.787234 (-8730 3985);
PAINT MONO (-8730 3985);
FORCEPROP 1 LAST PACK_TYPE 0402LF
J 2
(-8775 3875);
DISPLAY 0.510638 (-8775 3875);
FORCEPROP 1 LAST TOLERANCE 1%
J 2
(-8780 4075);
DISPLAY 0.510638 (-8780 4075);
FORCEPROP 1 LAST VALUE 1K
J 2
(-8780 4125);
DISPLAY 0.510638 (-8780 4125);
FORCEPROP 1 LAST MATERIAL CHIP
J 2
(-8775 3975);
DISPLAY 0.510638 (-8775 3975);
FORCEPROP 1 LAST WATTAGE 1/16W
J 2
(-8775 4025);
DISPLAY 0.510638 (-8775 4025);
FORCEPROP 2 LAST SEC_TYPE 0402LF
J 0
(-8775 4300);
DISPLAY 1.021277 (-8775 4300);
DISPLAY INVISIBLE (-8775 4300);
FORCEPROP 2 LAST CDS_LIB pure_quanta
J 2
(-8725 4075);
DISPLAY INVISIBLE (-8725 4075);
FORCEPROP 1 LAST PATH I128
J 2
(-8775 4250);
DISPLAY 0.978723 (-8775 4250);
PAINT WHITE (-8775 4250);
DISPLAY INVISIBLE (-8775 4250);
FORCEPROP 1 LAST PART_NUMBER CS21002FB06
J 2
(-8775 3925);
DISPLAY 0.510638 (-8775 3925);
DISPLAY INVISIBLE (-8775 3925);
FORCEADD Q_RES..1
(-4950 7875);
FORCEPROP 1 LAST LOCATION PR6608
J 0
(-5025 8050);
DISPLAY 0.808511 (-5025 8050);
FORCEPROP 2 LAST SEC 1
J 0
(-5000 8075);
DISPLAY 0.680851 (-5000 8075);
PAINT MONO (-5000 8075);
DISPLAY INVISIBLE (-5000 8075);
FORCEPROP 1 LASTPIN (-5050 7875) $PN 1
J 0
(-5038 7887);
DISPLAY 0.787234 (-5038 7887);
PAINT MONO (-5038 7887);
FORCEPROP 1 LASTPIN (-4850 7875) $PN 2
J 0
(-4888 7887);
DISPLAY 0.787234 (-4888 7887);
PAINT MONO (-4888 7887);
FORCEPROP 1 LAST PACK_TYPE 0402LF
J 0
(-4800 8000);
DISPLAY 0.510638 (-4800 8000);
FORCEPROP 1 LAST TOLERANCE 1%
J 0
(-4725 7875);
DISPLAY 0.510638 (-4725 7875);
FORCEPROP 1 LAST WATTAGE 1/16W
J 2
(-4825 8000);
DISPLAY 0.510638 (-4825 8000);
FORCEPROP 1 LAST VALUE 1
J 2
(-4775 7875);
DISPLAY 0.510638 (-4775 7875);
FORCEPROP 1 LAST MATERIAL CHIP
J 0
(-5075 8000);
DISPLAY 0.510638 (-5075 8000);
FORCEPROP 2 LAST SEC_TYPE 0402LF
J 0
(-5000 8075);
DISPLAY 1.021277 (-5000 8075);
DISPLAY INVISIBLE (-5000 8075);
FORCEPROP 2 LAST CDS_LIB pure_quanta
J 0
(-4950 7875);
DISPLAY INVISIBLE (-4950 7875);
FORCEPROP 1 LAST PATH I131
J 0
(-5000 8025);
DISPLAY 0.978723 (-5000 8025);
PAINT WHITE (-5000 8025);
DISPLAY INVISIBLE (-5000 8025);
FORCEPROP 1 LAST PART_NUMBER CS-1002FB04
J 0
(-5075 7950);
DISPLAY 0.510638 (-5075 7950);
DISPLAY INVISIBLE (-5075 7950);
FORCEADD Q_CAP..1
(-5275 7675);
FORCEPROP 1 LAST LOCATION PC6604
J 0
(-5225 7775);
DISPLAY 0.808511 (-5225 7775);
FORCEPROP 2 LAST SEC 1
J 0
(-5225 7875);
DISPLAY 0.680851 (-5225 7875);
PAINT MONO (-5225 7875);
DISPLAY INVISIBLE (-5225 7875);
FORCEPROP 1 LASTPIN (-5275 7775) $PN 1
J 0
(-5265 7755);
DISPLAY 0.787234 (-5265 7755);
PAINT MONO (-5265 7755);
FORCEPROP 1 LASTPIN (-5275 7575) $PN 2
J 0
(-5265 7555);
DISPLAY 0.787234 (-5265 7555);
PAINT MONO (-5265 7555);
FORCEPROP 1 LAST PACK_TYPE C0402
J 0
(-5225 7475);
DISPLAY 0.489362 (-5225 7475);
FORCEPROP 1 LAST VALUE 1UF
J 0
(-5225 7725);
DISPLAY 0.489362 (-5225 7725);
FORCEPROP 1 LAST VOLTAGE 16V
J 0
(-5225 7675);
DISPLAY 0.489362 (-5225 7675);
FORCEPROP 1 LAST TOLERANCE 10%
J 0
(-5225 7625);
DISPLAY 0.489362 (-5225 7625);
FORCEPROP 1 LAST MATERIAL X6S
J 0
(-5225 7575);
DISPLAY 0.489362 (-5225 7575);
FORCEPROP 2 LAST SEC_TYPE C0402
J 0
(-5225 7875);
DISPLAY 1.021277 (-5225 7875);
DISPLAY INVISIBLE (-5225 7875);
FORCEPROP 2 LAST CDS_LIB pure_quanta
J 0
(-5275 7675);
DISPLAY INVISIBLE (-5275 7675);
FORCEPROP 1 LAST PATH I132
J 0
(-5225 7825);
DISPLAY 0.978723 (-5225 7825);
PAINT WHITE (-5225 7825);
DISPLAY INVISIBLE (-5225 7825);
FORCEPROP 1 LAST PART_NUMBER CH5103KEB01
J 0
(-5225 7525);
DISPLAY 0.489362 (-5225 7525);
DISPLAY INVISIBLE (-5225 7525);
FORCEADD Q_RES..2
(-3525 3625);
FORCEPROP 1 LAST LOCATION PR6615
J 0
(-3480 3750);
DISPLAY 0.787234 (-3480 3750);
FORCEPROP 2 LAST SEC 1
J 0
(-3475 3850);
DISPLAY 0.680851 (-3475 3850);
PAINT MONO (-3475 3850);
DISPLAY INVISIBLE (-3475 3850);
FORCEPROP 1 LASTPIN (-3525 3725) $PN 1
J 0
(-3520 3687);
DISPLAY 0.787234 (-3520 3687);
PAINT MONO (-3520 3687);
FORCEPROP 1 LASTPIN (-3525 3525) $PN 2
J 0
(-3520 3535);
DISPLAY 0.787234 (-3520 3535);
PAINT MONO (-3520 3535);
FORCEPROP 1 LAST VALUE 1K
J 0
(-3470 3700);
DISPLAY 0.510638 (-3470 3700);
FORCEPROP 1 LAST PACK_TYPE 0402LF
J 0
(-3475 3450);
DISPLAY 0.510638 (-3475 3450);
FORCEPROP 1 LAST TOLERANCE 1%
J 0
(-3470 3650);
DISPLAY 0.510638 (-3470 3650);
FORCEPROP 1 LAST MATERIAL CHIP
J 0
(-3475 3550);
DISPLAY 0.510638 (-3475 3550);
FORCEPROP 1 LAST WATTAGE 1/16W
J 0
(-3475 3600);
DISPLAY 0.510638 (-3475 3600);
FORCEPROP 2 LAST CDS_LIB pure_quanta
J 2
(-3525 3625);
DISPLAY INVISIBLE (-3525 3625);
FORCEPROP 2 LAST SEC_TYPE 0402LF
J 0
(-3475 3850);
DISPLAY 1.021277 (-3475 3850);
DISPLAY INVISIBLE (-3475 3850);
FORCEPROP 1 LAST PATH I135
J 0
(-3475 3800);
DISPLAY 0.978723 (-3475 3800);
PAINT WHITE (-3475 3800);
DISPLAY INVISIBLE (-3475 3800);
FORCEPROP 1 LAST PART_NUMBER CS21002FB06
J 0
(-3475 3500);
DISPLAY 0.510638 (-3475 3500);
DISPLAY INVISIBLE (-3475 3500);
FORCEADD Q_RES..1
(-4775 3375);
FORCEPROP 1 LAST LOCATION PR6616
J 0
(-4975 3425);
DISPLAY 0.787234 (-4975 3425);
FORCEPROP 2 LAST SEC 1
J 0
(-4350 3575);
DISPLAY 0.680851 (-4350 3575);
PAINT MONO (-4350 3575);
DISPLAY INVISIBLE (-4350 3575);
FORCEPROP 1 LASTPIN (-4875 3375) $PN 1
J 0
(-4863 3387);
DISPLAY 0.787234 (-4863 3387);
PAINT MONO (-4863 3387);
FORCEPROP 1 LASTPIN (-4675 3375) $PN 2
J 0
(-4713 3387);
DISPLAY 0.787234 (-4713 3387);
PAINT MONO (-4713 3387);
FORCEPROP 1 LAST WATTAGE 1/16W
J 2
(-4825 3300);
DISPLAY 0.638298 (-4825 3300);
FORCEPROP 1 LAST TOLERANCE 5%
J 0
(-4475 3375);
DISPLAY 0.638298 (-4475 3375);
FORCEPROP 1 LAST MATERIAL CHIP
J 0
(-5150 3300);
DISPLAY 0.638298 (-5150 3300);
FORCEPROP 1 LAST VALUE 0
J 2
(-4600 3375);
DISPLAY 0.638298 (-4600 3375);
FORCEPROP 2 LAST SEC_TYPE 0402LF
J 0
(-4350 3575);
DISPLAY 1.021277 (-4350 3575);
DISPLAY INVISIBLE (-4350 3575);
FORCEPROP 2 LAST CDS_LIB pure_quanta
J 0
(-4775 3375);
DISPLAY INVISIBLE (-4775 3375);
FORCEPROP 1 LAST PACK_TYPE 0402LF
J 0
(-4825 3325);
DISPLAY 0.638298 (-4825 3325);
DISPLAY INVISIBLE (-4825 3325);
FORCEPROP 1 LAST PATH I136
J 0
(-4825 3525);
DISPLAY 0.978723 (-4825 3525);
PAINT WHITE (-4825 3525);
DISPLAY INVISIBLE (-4825 3525);
FORCEPROP 1 LAST PART_NUMBER CS00002JB13
J 0
(-4750 3300);
DISPLAY 0.638298 (-4750 3300);
DISPLAY INVISIBLE (-4750 3300);
FORCEADD Q_RES..2
(-4600 2475);
FORCEPROP 1 LAST LOCATION PR6814
J 0
(-4555 2600);
DISPLAY 0.787234 (-4555 2600);
FORCEPROP 2 LAST SEC 1
J 0
(-4550 2700);
DISPLAY 0.680851 (-4550 2700);
PAINT MONO (-4550 2700);
DISPLAY INVISIBLE (-4550 2700);
FORCEPROP 1 LASTPIN (-4600 2575) $PN 1
J 0
(-4595 2537);
DISPLAY 0.787234 (-4595 2537);
PAINT MONO (-4595 2537);
FORCEPROP 1 LASTPIN (-4600 2375) $PN 2
J 0
(-4595 2385);
DISPLAY 0.787234 (-4595 2385);
PAINT MONO (-4595 2385);
FORCEPROP 1 LAST WATTAGE 1/16W
J 0
(-4560 2450);
DISPLAY 0.510638 (-4560 2450);
FORCEPROP 1 LAST MATERIAL EMPTY
J 0
(-4560 2400);
DISPLAY 0.510638 (-4560 2400);
FORCEPROP 1 LAST PACK_TYPE 0402LF
J 0
(-4560 2300);
DISPLAY 0.510638 (-4560 2300);
FORCEPROP 1 LAST VALUE 10K
J 0
(-4555 2550);
DISPLAY 0.510638 (-4555 2550);
FORCEPROP 1 LAST TOLERANCE 1%
J 0
(-4555 2500);
DISPLAY 0.510638 (-4555 2500);
FORCEPROP 2 LAST SEC_TYPE 0402LF
J 0
(-4550 2700);
DISPLAY 1.021277 (-4550 2700);
DISPLAY INVISIBLE (-4550 2700);
FORCEPROP 2 LAST CDS_LIB pure_quanta
J 0
(-4600 2475);
DISPLAY INVISIBLE (-4600 2475);
FORCEPROP 1 LAST PATH I138
J 0
(-4550 2650);
DISPLAY 0.978723 (-4550 2650);
PAINT WHITE (-4550 2650);
DISPLAY INVISIBLE (-4550 2650);
FORCEPROP 1 LAST PART_NUMBER CS31002FB08
J 0
(-4560 2350);
DISPLAY 0.510638 (-4560 2350);
DISPLAY INVISIBLE (-4560 2350);
FORCEADD Q_CAP..1
(-5675 7675);
FORCEPROP 1 LAST LOCATION PC6603
J 0
(-5625 7775);
DISPLAY 0.808511 (-5625 7775);
FORCEPROP 2 LAST SEC 1
J 0
(-5625 7875);
DISPLAY 0.680851 (-5625 7875);
PAINT MONO (-5625 7875);
DISPLAY INVISIBLE (-5625 7875);
FORCEPROP 1 LASTPIN (-5675 7775) $PN 1
J 0
(-5665 7755);
DISPLAY 0.787234 (-5665 7755);
PAINT MONO (-5665 7755);
FORCEPROP 1 LASTPIN (-5675 7575) $PN 2
J 0
(-5665 7555);
DISPLAY 0.787234 (-5665 7555);
PAINT MONO (-5665 7555);
FORCEPROP 1 LAST PACK_TYPE C0402
J 0
(-5625 7475);
DISPLAY 0.510638 (-5625 7475);
FORCEPROP 1 LAST VALUE 100NF
J 0
(-5625 7725);
DISPLAY 0.510638 (-5625 7725);
FORCEPROP 1 LAST VOLTAGE 50V
J 0
(-5625 7675);
DISPLAY 0.510638 (-5625 7675);
FORCEPROP 1 LAST MATERIAL X7R
J 0
(-5625 7575);
DISPLAY 0.510638 (-5625 7575);
FORCEPROP 1 LAST TOLERANCE 10%
J 0
(-5625 7625);
DISPLAY 0.510638 (-5625 7625);
FORCEPROP 2 LAST CDS_LIB pure_quanta
J 0
(-5675 7675);
DISPLAY INVISIBLE (-5675 7675);
FORCEPROP 2 LAST SEC_TYPE C0402
J 0
(-5625 7875);
DISPLAY 1.021277 (-5625 7875);
DISPLAY INVISIBLE (-5625 7875);
FORCEPROP 1 LAST PATH I144
J 0
(-5625 7825);
DISPLAY 0.978723 (-5625 7825);
PAINT WHITE (-5625 7825);
DISPLAY INVISIBLE (-5625 7825);
FORCEPROP 1 LAST PART_NUMBER CH4106K1B01
J 0
(-5625 7525);
DISPLAY 0.510638 (-5625 7525);
DISPLAY INVISIBLE (-5625 7525);
FORCEADD Q_CAP..1
(-5675 7200);
FORCEPROP 1 LAST LOCATION PC6606
J 0
(-5625 7300);
DISPLAY 0.808511 (-5625 7300);
FORCEPROP 2 LAST SEC 1
J 0
(-5625 7400);
DISPLAY 0.680851 (-5625 7400);
PAINT MONO (-5625 7400);
DISPLAY INVISIBLE (-5625 7400);
FORCEPROP 1 LASTPIN (-5675 7300) $PN 1
J 0
(-5665 7280);
DISPLAY 0.787234 (-5665 7280);
PAINT MONO (-5665 7280);
FORCEPROP 1 LASTPIN (-5675 7100) $PN 2
J 0
(-5665 7080);
DISPLAY 0.787234 (-5665 7080);
PAINT MONO (-5665 7080);
FORCEPROP 1 LAST VALUE 10UF
J 0
(-5625 7250);
DISPLAY 0.510638 (-5625 7250);
FORCEPROP 1 LAST MATERIAL X6S
J 0
(-5625 7100);
DISPLAY 0.510638 (-5625 7100);
FORCEPROP 1 LAST VOLTAGE 6.3V
J 0
(-5625 7200);
DISPLAY 0.510638 (-5625 7200);
FORCEPROP 1 LAST TOLERANCE 20%
J 0
(-5625 7150);
DISPLAY 0.510638 (-5625 7150);
FORCEPROP 1 LAST PACK_TYPE C0402
J 0
(-5625 7000);
DISPLAY 0.510638 (-5625 7000);
FORCEPROP 2 LAST SEC_TYPE C0402
J 0
(-5625 7400);
DISPLAY 1.021277 (-5625 7400);
DISPLAY INVISIBLE (-5625 7400);
FORCEPROP 2 LAST CDS_LIB pure_quanta
J 0
(-5675 7200);
DISPLAY INVISIBLE (-5675 7200);
FORCEPROP 1 LAST PATH I145
J 0
(-5625 7350);
DISPLAY 0.978723 (-5625 7350);
PAINT WHITE (-5625 7350);
DISPLAY INVISIBLE (-5625 7350);
FORCEPROP 1 LAST PART_NUMBER CH6101MEB03
J 0
(-5625 7050);
DISPLAY 0.510638 (-5625 7050);
DISPLAY INVISIBLE (-5625 7050);
FORCEADD Q_CAP..1
(-5275 7200);
FORCEPROP 1 LAST LOCATION PC6605
J 0
(-5225 7300);
DISPLAY 0.787234 (-5225 7300);
FORCEPROP 2 LAST SEC 1
J 0
(-5225 7400);
DISPLAY 0.680851 (-5225 7400);
PAINT MONO (-5225 7400);
DISPLAY INVISIBLE (-5225 7400);
FORCEPROP 1 LASTPIN (-5275 7300) $PN 1
J 0
(-5265 7280);
DISPLAY 0.787234 (-5265 7280);
PAINT MONO (-5265 7280);
FORCEPROP 1 LASTPIN (-5275 7100) $PN 2
J 0
(-5265 7080);
DISPLAY 0.787234 (-5265 7080);
PAINT MONO (-5265 7080);
FORCEPROP 1 LAST PACK_TYPE C0402
J 0
(-5225 7000);
DISPLAY 0.489362 (-5225 7000);
FORCEPROP 1 LAST MATERIAL X6S
J 0
(-5225 7100);
DISPLAY 0.489362 (-5225 7100);
FORCEPROP 1 LAST TOLERANCE 10%
J 0
(-5225 7150);
DISPLAY 0.489362 (-5225 7150);
FORCEPROP 1 LAST VOLTAGE 16V
J 0
(-5225 7200);
DISPLAY 0.489362 (-5225 7200);
FORCEPROP 1 LAST VALUE 1UF
J 0
(-5225 7250);
DISPLAY 0.489362 (-5225 7250);
FORCEPROP 2 LAST SEC_TYPE C0402
J 0
(-5225 7400);
DISPLAY 1.021277 (-5225 7400);
DISPLAY INVISIBLE (-5225 7400);
FORCEPROP 2 LAST CDS_LIB pure_quanta
J 0
(-5275 7200);
DISPLAY INVISIBLE (-5275 7200);
FORCEPROP 1 LAST PATH I146
J 0
(-5225 7350);
DISPLAY 0.978723 (-5225 7350);
PAINT WHITE (-5225 7350);
DISPLAY INVISIBLE (-5225 7350);
FORCEPROP 1 LAST PART_NUMBER CH5103KEB01
J 0
(-5225 7050);
DISPLAY 0.489362 (-5225 7050);
DISPLAY INVISIBLE (-5225 7050);
FORCEADD Q_CAP..1
(-5300 2475);
FORCEPROP 1 LAST LOCATION PC6607
J 0
(-5250 2575);
DISPLAY 0.808511 (-5250 2575);
FORCEPROP 2 LAST SEC 1
J 0
(-5250 2675);
DISPLAY 0.680851 (-5250 2675);
PAINT MONO (-5250 2675);
DISPLAY INVISIBLE (-5250 2675);
FORCEPROP 1 LASTPIN (-5300 2575) $PN 1
J 0
(-5290 2555);
DISPLAY 0.787234 (-5290 2555);
PAINT MONO (-5290 2555);
FORCEPROP 1 LASTPIN (-5300 2375) $PN 2
J 0
(-5290 2355);
DISPLAY 0.787234 (-5290 2355);
PAINT MONO (-5290 2355);
FORCEPROP 1 LAST MATERIAL X7R
J 0
(-5250 2375);
DISPLAY 0.510638 (-5250 2375);
FORCEPROP 1 LAST PACK_TYPE 0402
J 0
(-5250 2275);
DISPLAY 0.510638 (-5250 2275);
FORCEPROP 1 LAST VALUE 470PF
J 0
(-5250 2525);
DISPLAY 0.510638 (-5250 2525);
FORCEPROP 1 LAST TOLERANCE 10%
J 0
(-5250 2425);
DISPLAY 0.510638 (-5250 2425);
FORCEPROP 1 LAST VOLTAGE 50V
J 0
(-5250 2475);
DISPLAY 0.510638 (-5250 2475);
FORCEPROP 2 LAST SEC_TYPE 0402
J 0
(-5250 2675);
DISPLAY 1.021277 (-5250 2675);
DISPLAY INVISIBLE (-5250 2675);
FORCEPROP 2 LAST CDS_LIB pure_quanta
J 0
(-5300 2475);
DISPLAY INVISIBLE (-5300 2475);
FORCEPROP 1 LAST PATH I148
J 0
(-5250 2625);
DISPLAY 0.978723 (-5250 2625);
PAINT WHITE (-5250 2625);
DISPLAY INVISIBLE (-5250 2625);
FORCEPROP 1 LAST PART_NUMBER TMP_QCH14706KB18
J 0
(-5250 2325);
DISPLAY 0.510638 (-5250 2325);
DISPLAY INVISIBLE (-5250 2325);
FORCEADD Q_RES..2
R 2
(-8800 2100);
FORCEPROP 1 LAST LOCATION PR6605
J 2
(-8875 2175);
DISPLAY 0.787234 (-8875 2175);
FORCEPROP 2 LAST SEC 1
J 2
(-8850 2325);
DISPLAY 0.680851 (-8850 2325);
PAINT MONO (-8850 2325);
DISPLAY INVISIBLE (-8850 2325);
FORCEPROP 1 LASTPIN (-8800 2200) $PN 1
J 2
(-8805 2162);
DISPLAY 0.787234 (-8805 2162);
PAINT MONO (-8805 2162);
FORCEPROP 1 LASTPIN (-8800 2000) $PN 2
J 2
(-8805 2010);
DISPLAY 0.787234 (-8805 2010);
PAINT MONO (-8805 2010);
FORCEPROP 1 LAST PACK_TYPE 0402LF
J 2
(-8840 1925);
DISPLAY 0.510638 (-8840 1925);
FORCEPROP 1 LAST VALUE 0
J 2
(-8845 2175);
DISPLAY 0.510638 (-8845 2175);
FORCEPROP 1 LAST TOLERANCE 5%
J 2
(-8845 2125);
DISPLAY 0.510638 (-8845 2125);
FORCEPROP 1 LAST WATTAGE 1/16W
J 2
(-8840 2075);
DISPLAY 0.510638 (-8840 2075);
FORCEPROP 1 LAST MATERIAL CHIP
J 2
(-8840 2025);
DISPLAY 0.510638 (-8840 2025);
FORCEPROP 2 LAST SEC_TYPE 0402LF
J 2
(-8850 2325);
DISPLAY 1.021277 (-8850 2325);
DISPLAY INVISIBLE (-8850 2325);
FORCEPROP 2 LAST CDS_LIB pure_quanta
J 2
(-8800 2100);
DISPLAY INVISIBLE (-8800 2100);
FORCEPROP 1 LAST PATH I150
J 2
(-8850 2275);
DISPLAY 0.978723 (-8850 2275);
PAINT WHITE (-8850 2275);
DISPLAY INVISIBLE (-8850 2275);
FORCEPROP 1 LAST PART_NUMBER CS00002JB13
J 2
(-8840 1975);
DISPLAY 0.510638 (-8840 1975);
DISPLAY INVISIBLE (-8840 1975);
FORCEADD Q_CAP..1
(-8675 2100);
FORCEPROP 1 LAST LOCATION PC6601
J 0
(-8625 2200);
DISPLAY 0.808511 (-8625 2200);
FORCEPROP 2 LAST SEC 1
J 0
(-8625 2300);
DISPLAY 0.680851 (-8625 2300);
PAINT MONO (-8625 2300);
DISPLAY INVISIBLE (-8625 2300);
FORCEPROP 1 LASTPIN (-8675 2200) $PN 1
J 0
(-8665 2180);
DISPLAY 0.787234 (-8665 2180);
PAINT MONO (-8665 2180);
FORCEPROP 1 LASTPIN (-8675 2000) $PN 2
J 0
(-8665 1980);
DISPLAY 0.787234 (-8665 1980);
PAINT MONO (-8665 1980);
FORCEPROP 1 LAST MATERIAL EMPTY
J 0
(-8625 2000);
DISPLAY 0.510638 (-8625 2000);
FORCEPROP 1 LAST PACK_TYPE 0402
J 0
(-8625 1900);
DISPLAY 0.510638 (-8625 1900);
FORCEPROP 1 LAST TOLERANCE 10%
J 0
(-8625 2050);
DISPLAY 0.510638 (-8625 2050);
FORCEPROP 1 LAST VALUE 0.1UF
J 0
(-8625 2150);
DISPLAY 0.510638 (-8625 2150);
FORCEPROP 1 LAST VOLTAGE 25V
J 0
(-8625 2100);
DISPLAY 0.510638 (-8625 2100);
FORCEPROP 2 LAST SEC_TYPE 0402
J 0
(-8625 2300);
DISPLAY 1.021277 (-8625 2300);
DISPLAY INVISIBLE (-8625 2300);
FORCEPROP 2 LAST CDS_LIB pure_quanta
J 0
(-8675 2100);
DISPLAY INVISIBLE (-8675 2100);
FORCEPROP 1 LAST PATH I151
J 0
(-8625 2250);
DISPLAY 0.978723 (-8625 2250);
PAINT WHITE (-8625 2250);
DISPLAY INVISIBLE (-8625 2250);
FORCEPROP 1 LAST PART_NUMBER CH4104K1B00
J 0
(-8625 1950);
DISPLAY 0.510638 (-8625 1950);
DISPLAY INVISIBLE (-8625 1950);
FORCEADD UNIVERSAL_GND..1
R 5
(-9150 6800);
FORCEPROP 3 LASTPIN (-9100 6800) SIG_NAME GND\g
J 0
(-9090 6810);
DISPLAY 0.659574 (-9090 6810);
PAINT MONO (-9090 6810);
DISPLAY INVISIBLE (-9090 6810);
FORCEPROP 2 LAST CDS_LIB pure_quanta_power
R 3
J 0
(-9150 6800);
DISPLAY INVISIBLE (-9150 6800);
FORCEPROP 1 LAST HDL_POWER GND
R 3
J 1
(-9225 6775);
DISPLAY 0.872340 (-9225 6775);
PAINT GREEN (-9225 6775);
DISPLAY INVISIBLE (-9225 6775);
FORCEPROP 1 LAST PATH I154
R 3
J 0
(-9150 6725);
DISPLAY 0.872340 (-9150 6725);
PAINT AQUA (-9150 6725);
DISPLAY INVISIBLE (-9150 6725);
FORCEADD Q_RES..1
(-9100 2525);
FORCEPROP 1 LAST LOCATION PR6807
J 0
(-9350 2525);
DISPLAY 0.787234 (-9350 2525);
FORCEPROP 2 LAST SEC 1
J 0
(-9150 2725);
DISPLAY 0.680851 (-9150 2725);
PAINT MONO (-9150 2725);
DISPLAY INVISIBLE (-9150 2725);
FORCEPROP 1 LASTPIN (-9200 2525) $PN 1
J 0
(-9188 2537);
DISPLAY 0.787234 (-9188 2537);
PAINT MONO (-9188 2537);
FORCEPROP 1 LASTPIN (-9000 2525) $PN 2
J 0
(-9038 2537);
DISPLAY 0.787234 (-9038 2537);
PAINT MONO (-9038 2537);
FORCEPROP 1 LAST MATERIAL EMPTY
J 0
(-9150 2600);
DISPLAY 0.638298 (-9150 2600);
FORCEPROP 1 LAST TOLERANCE 5%
J 0
(-8850 2525);
DISPLAY 0.638298 (-8850 2525);
FORCEPROP 1 LAST VALUE 0
J 2
(-8900 2525);
DISPLAY 0.638298 (-8900 2525);
FORCEPROP 1 LAST WATTAGE 1/16W
J 2
(-8900 2700);
DISPLAY 0.638298 (-8900 2700);
DISPLAY INVISIBLE (-8900 2700);
FORCEPROP 1 LAST PACK_TYPE 0402LF
J 0
(-8850 2700);
DISPLAY 0.638298 (-8850 2700);
DISPLAY INVISIBLE (-8850 2700);
FORCEPROP 2 LAST SEC_TYPE 0402LF
J 0
(-9150 2725);
DISPLAY 1.021277 (-9150 2725);
DISPLAY INVISIBLE (-9150 2725);
FORCEPROP 2 LAST CDS_LIB pure_quanta
J 0
(-9100 2525);
DISPLAY INVISIBLE (-9100 2525);
FORCEPROP 1 LAST PATH I158
J 0
(-9150 2675);
DISPLAY 0.978723 (-9150 2675);
PAINT WHITE (-9150 2675);
DISPLAY INVISIBLE (-9150 2675);
FORCEPROP 1 LAST PART_NUMBER CS00002JB13
J 0
(-9225 2625);
DISPLAY 0.638298 (-9225 2625);
DISPLAY INVISIBLE (-9225 2625);
FORCEADD VCC15..1
(-9500 2650);
FORCEPROP 3 LASTPIN (-9500 2600) SIG_NAME P12V_AUX\g
J 0
(-9490 2610);
DISPLAY 0.659574 (-9490 2610);
PAINT MONO (-9490 2610);
DISPLAY INVISIBLE (-9490 2610);
FORCEPROP 1 LAST HDL_POWER P12V_AUX
J 1
(-9500 2700);
DISPLAY 0.617021 (-9500 2700);
PAINT GREEN (-9500 2700);
FORCEPROP 2 LAST CDS_LIB pure_quanta_power
J 0
(-9500 2650);
DISPLAY INVISIBLE (-9500 2650);
FORCEPROP 1 LAST PATH I159
J 0
(-9450 2675);
DISPLAY 0.872340 (-9450 2675);
PAINT AQUA (-9450 2675);
DISPLAY INVISIBLE (-9450 2675);
FORCEADD OFFPAGE..1
(-11100 6725);
FORCEPROP 2 LAST $XR0 151 
J 0
(-11382 6725);
DISPLAY 0.638298 (-11382 6725);
PAINT MONO (-11382 6725);
FORCEPROP 2 LAST CDS_LIB standard
J 0
(-11100 6725);
DISPLAY INVISIBLE (-11100 6725);
FORCEPROP 1 LAST OFFPAGE TRUE
J 0
(-10775 6600);
DISPLAY 0.872340 (-10775 6600);
PAINT GREEN (-10775 6600);
DISPLAY INVISIBLE (-10775 6600);
FORCEPROP 1 LAST COMMENT_BODY TRUE
J 0
(-10975 6625);
DISPLAY 0.872340 (-10975 6625);
PAINT GREEN (-10975 6625);
DISPLAY INVISIBLE (-10975 6625);
FORCEPROP 2 LAST PATH I16
J 0
(-11350 6775);
DISPLAY 1.021277 (-11350 6775);
DISPLAY INVISIBLE (-11350 6775);
FORCEADD Q_RES..1
(-9100 2425);
FORCEPROP 1 LAST LOCATION PR6606
J 0
(-9350 2425);
DISPLAY 0.787234 (-9350 2425);
FORCEPROP 2 LAST SEC 1
J 0
(-9150 2625);
DISPLAY 0.680851 (-9150 2625);
PAINT MONO (-9150 2625);
DISPLAY INVISIBLE (-9150 2625);
FORCEPROP 1 LASTPIN (-9200 2425) $PN 1
J 0
(-9188 2437);
DISPLAY 0.787234 (-9188 2437);
PAINT MONO (-9188 2437);
FORCEPROP 1 LASTPIN (-9000 2425) $PN 2
J 0
(-9038 2437);
DISPLAY 0.787234 (-9038 2437);
PAINT MONO (-9038 2437);
FORCEPROP 1 LAST VALUE 0
J 2
(-8900 2425);
DISPLAY 0.638298 (-8900 2425);
FORCEPROP 1 LAST TOLERANCE 5%
J 0
(-8850 2425);
DISPLAY 0.638298 (-8850 2425);
FORCEPROP 1 LAST MATERIAL CHIP
J 0
(-9225 2550);
DISPLAY 0.510638 (-9225 2550);
DISPLAY INVISIBLE (-9225 2550);
FORCEPROP 1 LAST WATTAGE 1/16W
J 2
(-8975 2550);
DISPLAY 0.510638 (-8975 2550);
DISPLAY INVISIBLE (-8975 2550);
FORCEPROP 1 LAST PACK_TYPE 0402LF
J 0
(-8950 2550);
DISPLAY 0.510638 (-8950 2550);
DISPLAY INVISIBLE (-8950 2550);
FORCEPROP 2 LAST SEC_TYPE 0402LF
J 0
(-9150 2625);
DISPLAY 1.021277 (-9150 2625);
DISPLAY INVISIBLE (-9150 2625);
FORCEPROP 2 LAST CDS_LIB pure_quanta
J 0
(-9100 2425);
DISPLAY INVISIBLE (-9100 2425);
FORCEPROP 1 LAST PATH I160
J 0
(-9150 2575);
DISPLAY 0.978723 (-9150 2575);
PAINT WHITE (-9150 2575);
DISPLAY INVISIBLE (-9150 2575);
FORCEPROP 1 LAST PART_NUMBER CS00002JB13
J 0
(-9225 2500);
DISPLAY 0.510638 (-9225 2500);
DISPLAY INVISIBLE (-9225 2500);
FORCEADD Q_RES..1
(-10175 3400);
FORCEPROP 1 LAST LOCATION R6801
J 0
(-10450 3400);
DISPLAY 0.787234 (-10450 3400);
FORCEPROP 2 LAST SEC 1
J 0
(-10225 3600);
DISPLAY 0.680851 (-10225 3600);
PAINT MONO (-10225 3600);
DISPLAY INVISIBLE (-10225 3600);
FORCEPROP 1 LASTPIN (-10275 3400) $PN 1
J 0
(-10263 3412);
DISPLAY 0.787234 (-10263 3412);
PAINT MONO (-10263 3412);
FORCEPROP 1 LASTPIN (-10075 3400) $PN 2
J 0
(-10113 3412);
DISPLAY 0.787234 (-10113 3412);
PAINT MONO (-10113 3412);
FORCEPROP 1 LAST MATERIAL CHIP
J 0
(-10300 3325);
DISPLAY 0.638298 (-10300 3325);
FORCEPROP 1 LAST WATTAGE 1/16W
J 2
(-9975 3325);
DISPLAY 0.638298 (-9975 3325);
FORCEPROP 1 LAST PACK_TYPE 0402LF
J 0
(-9950 3325);
DISPLAY 0.638298 (-9950 3325);
FORCEPROP 1 LAST TOLERANCE 5%
J 0
(-9900 3400);
DISPLAY 0.510638 (-9900 3400);
FORCEPROP 1 LAST VALUE 0
J 2
(-9950 3400);
DISPLAY 0.510638 (-9950 3400);
FORCEPROP 2 LAST SEC_TYPE 0402LF
J 0
(-10225 3600);
DISPLAY 1.021277 (-10225 3600);
DISPLAY INVISIBLE (-10225 3600);
FORCEPROP 2 LAST CDS_LIB pure_quanta
J 0
(-10175 3400);
DISPLAY INVISIBLE (-10175 3400);
FORCEPROP 1 LAST PATH I161
J 0
(-10225 3550);
DISPLAY 0.978723 (-10225 3550);
PAINT WHITE (-10225 3550);
DISPLAY INVISIBLE (-10225 3550);
FORCEPROP 1 LAST PART_NUMBER CS00002JB13
J 0
(-10300 3275);
DISPLAY 0.638298 (-10300 3275);
DISPLAY INVISIBLE (-10300 3275);
FORCEADD UNIVERSAL_GND..1
R 5
(-10675 3400);
FORCEPROP 3 LASTPIN (-10625 3400) SIG_NAME GND\g
J 0
(-10615 3410);
DISPLAY 0.659574 (-10615 3410);
PAINT MONO (-10615 3410);
DISPLAY INVISIBLE (-10615 3410);
FORCEPROP 2 LAST CDS_LIB pure_quanta_power
J 0
(-10675 3400);
DISPLAY INVISIBLE (-10675 3400);
FORCEPROP 1 LAST HDL_POWER GND
R 3
J 1
(-10750 3375);
DISPLAY 0.872340 (-10750 3375);
PAINT GREEN (-10750 3375);
DISPLAY INVISIBLE (-10750 3375);
FORCEPROP 1 LAST PATH I162
R 3
J 0
(-10675 3325);
DISPLAY 0.872340 (-10675 3325);
PAINT AQUA (-10675 3325);
DISPLAY INVISIBLE (-10675 3325);
FORCEADD VCC15..1
(-9875 7550);
FORCEPROP 3 LASTPIN (-9875 7500) SIG_NAME P3V3_AUX\g
J 0
(-9865 7510);
DISPLAY 0.659574 (-9865 7510);
PAINT MONO (-9865 7510);
DISPLAY INVISIBLE (-9865 7510);
FORCEPROP 1 LAST HDL_POWER P3V3_AUX
J 1
(-9875 7600);
DISPLAY 0.617021 (-9875 7600);
PAINT GREEN (-9875 7600);
FORCEPROP 2 LAST CDS_LIB pure_quanta_power
J 0
(-9875 7550);
DISPLAY INVISIBLE (-9875 7550);
FORCEPROP 1 LAST PATH I164
J 0
(-9825 7575);
DISPLAY 0.872340 (-9825 7575);
PAINT AQUA (-9825 7575);
DISPLAY INVISIBLE (-9825 7575);
FORCEADD Q_RES..2
(-9000 6950);
FORCEPROP 1 LAST LOCATION PR6810
J 0
(-8955 7075);
DISPLAY 0.638298 (-8955 7075);
FORCEPROP 2 LAST SEC 1
J 0
(-8950 7175);
DISPLAY 0.680851 (-8950 7175);
PAINT MONO (-8950 7175);
DISPLAY INVISIBLE (-8950 7175);
FORCEPROP 1 LASTPIN (-9000 7050) $PN 1
J 0
(-8995 7012);
DISPLAY 0.787234 (-8995 7012);
PAINT MONO (-8995 7012);
FORCEPROP 1 LASTPIN (-9000 6850) $PN 2
J 0
(-8995 6860);
DISPLAY 0.787234 (-8995 6860);
PAINT MONO (-8995 6860);
FORCEPROP 1 LAST PACK_TYPE 0402LF
J 0
(-8960 6775);
DISPLAY 0.510638 (-8960 6775);
FORCEPROP 1 LAST MATERIAL CHIP
J 0
(-8960 6875);
DISPLAY 0.510638 (-8960 6875);
FORCEPROP 1 LAST VALUE 0
J 0
(-8955 7025);
DISPLAY 0.510638 (-8955 7025);
FORCEPROP 1 LAST TOLERANCE 5%
J 0
(-8955 6975);
DISPLAY 0.510638 (-8955 6975);
FORCEPROP 1 LAST WATTAGE 1/16W
J 0
(-8960 6925);
DISPLAY 0.510638 (-8960 6925);
FORCEPROP 2 LAST CDS_LIB pure_quanta
J 0
(-9000 6950);
DISPLAY INVISIBLE (-9000 6950);
FORCEPROP 2 LAST SEC_TYPE 0402LF
J 0
(-8950 7175);
DISPLAY 1.021277 (-8950 7175);
DISPLAY INVISIBLE (-8950 7175);
FORCEPROP 1 LAST PATH I165
J 0
(-8950 7125);
DISPLAY 0.978723 (-8950 7125);
PAINT WHITE (-8950 7125);
DISPLAY INVISIBLE (-8950 7125);
FORCEPROP 1 LAST PART_NUMBER CS00002JB13
J 0
(-8960 6825);
DISPLAY 0.510638 (-8960 6825);
DISPLAY INVISIBLE (-8960 6825);
FORCEADD Q_RES..1
(-9375 7425);
FORCEPROP 1 LAST LOCATION PR6805
J 0
(-9625 7425);
DISPLAY 0.638298 (-9625 7425);
FORCEPROP 2 LAST SEC 1
J 0
(-9425 7625);
DISPLAY 0.680851 (-9425 7625);
PAINT MONO (-9425 7625);
DISPLAY INVISIBLE (-9425 7625);
FORCEPROP 1 LASTPIN (-9475 7425) $PN 1
J 0
(-9463 7437);
DISPLAY 0.787234 (-9463 7437);
PAINT MONO (-9463 7437);
FORCEPROP 1 LASTPIN (-9275 7425) $PN 2
J 0
(-9313 7437);
DISPLAY 0.787234 (-9313 7437);
PAINT MONO (-9313 7437);
FORCEPROP 1 LAST MATERIAL EMPTY
J 0
(-9475 7575);
DISPLAY 0.510638 (-9475 7575);
FORCEPROP 1 LAST VALUE 1K
J 2
(-9150 7425);
DISPLAY 0.510638 (-9150 7425);
FORCEPROP 1 LAST TOLERANCE 1%
J 0
(-9100 7425);
DISPLAY 0.510638 (-9100 7425);
FORCEPROP 1 LAST WATTAGE 1/16W
J 2
(-9200 7575);
DISPLAY 0.510638 (-9200 7575);
FORCEPROP 1 LAST PACK_TYPE 0402LF
J 0
(-9150 7575);
DISPLAY 0.510638 (-9150 7575);
FORCEPROP 2 LAST CDS_LIB pure_quanta
J 0
(-9375 7425);
DISPLAY INVISIBLE (-9375 7425);
FORCEPROP 2 LAST SEC_TYPE 0402LF
J 0
(-9425 7625);
DISPLAY 1.021277 (-9425 7625);
DISPLAY INVISIBLE (-9425 7625);
FORCEPROP 1 LAST PATH I166
J 0
(-9425 7575);
DISPLAY 0.978723 (-9425 7575);
PAINT WHITE (-9425 7575);
DISPLAY INVISIBLE (-9425 7575);
FORCEPROP 1 LAST PART_NUMBER CS21002FB06
J 0
(-9475 7525);
DISPLAY 0.510638 (-9475 7525);
DISPLAY INVISIBLE (-9475 7525);
FORCEADD Q_RES..1
(-9375 7275);
FORCEPROP 1 LAST LOCATION PR6803
J 0
(-9625 7275);
DISPLAY 0.638298 (-9625 7275);
FORCEPROP 2 LAST SEC 1
J 0
(-9425 7475);
DISPLAY 0.680851 (-9425 7475);
PAINT MONO (-9425 7475);
DISPLAY INVISIBLE (-9425 7475);
FORCEPROP 1 LASTPIN (-9475 7275) $PN 1
J 0
(-9463 7287);
DISPLAY 0.787234 (-9463 7287);
PAINT MONO (-9463 7287);
FORCEPROP 1 LASTPIN (-9275 7275) $PN 2
J 0
(-9313 7287);
DISPLAY 0.787234 (-9313 7287);
PAINT MONO (-9313 7287);
FORCEPROP 1 LAST TOLERANCE 1%
J 0
(-9100 7275);
DISPLAY 0.510638 (-9100 7275);
FORCEPROP 1 LAST VALUE 1K
J 2
(-9150 7275);
DISPLAY 0.510638 (-9150 7275);
FORCEPROP 1 LAST MATERIAL EMPTY
J 0
(-9425 7300);
DISPLAY 0.510638 (-9425 7300);
FORCEPROP 1 LAST PACK_TYPE 0402LF
J 0
(-9150 7425);
DISPLAY 0.510638 (-9150 7425);
DISPLAY INVISIBLE (-9150 7425);
FORCEPROP 2 LAST SEC_TYPE 0402LF
J 0
(-9425 7475);
DISPLAY 1.021277 (-9425 7475);
DISPLAY INVISIBLE (-9425 7475);
FORCEPROP 1 LAST WATTAGE 1/16W
J 2
(-9200 7425);
DISPLAY 0.510638 (-9200 7425);
DISPLAY INVISIBLE (-9200 7425);
FORCEPROP 2 LAST CDS_LIB pure_quanta
J 0
(-9375 7275);
DISPLAY INVISIBLE (-9375 7275);
FORCEPROP 1 LAST PATH I167
J 0
(-9425 7425);
DISPLAY 0.978723 (-9425 7425);
PAINT WHITE (-9425 7425);
DISPLAY INVISIBLE (-9425 7425);
FORCEPROP 1 LAST PART_NUMBER CS21002FB06
J 0
(-9475 7375);
DISPLAY 0.510638 (-9475 7375);
DISPLAY INVISIBLE (-9475 7375);
FORCEADD Q_RES..2
(-8650 6950);
FORCEPROP 1 LAST LOCATION PR6819
J 0
(-8605 7075);
DISPLAY 0.638298 (-8605 7075);
FORCEPROP 2 LAST SEC 1
J 0
(-8600 7175);
DISPLAY 0.680851 (-8600 7175);
PAINT MONO (-8600 7175);
DISPLAY INVISIBLE (-8600 7175);
FORCEPROP 1 LASTPIN (-8650 7050) $PN 1
J 0
(-8645 7012);
DISPLAY 0.787234 (-8645 7012);
PAINT MONO (-8645 7012);
FORCEPROP 1 LASTPIN (-8650 6850) $PN 2
J 0
(-8645 6860);
DISPLAY 0.787234 (-8645 6860);
PAINT MONO (-8645 6860);
FORCEPROP 1 LAST PACK_TYPE 0402LF
J 0
(-8610 6775);
DISPLAY 0.510638 (-8610 6775);
FORCEPROP 1 LAST TOLERANCE 5%
J 0
(-8605 6975);
DISPLAY 0.510638 (-8605 6975);
FORCEPROP 1 LAST MATERIAL CHIP
J 0
(-8610 6875);
DISPLAY 0.510638 (-8610 6875);
FORCEPROP 1 LAST VALUE 0
J 0
(-8605 7025);
DISPLAY 0.510638 (-8605 7025);
FORCEPROP 1 LAST WATTAGE 1/16W
J 0
(-8610 6925);
DISPLAY 0.510638 (-8610 6925);
FORCEPROP 2 LAST CDS_LIB pure_quanta
J 0
(-8650 6950);
DISPLAY INVISIBLE (-8650 6950);
FORCEPROP 2 LAST SEC_TYPE 0402LF
J 0
(-8600 7175);
DISPLAY 1.021277 (-8600 7175);
DISPLAY INVISIBLE (-8600 7175);
FORCEPROP 1 LAST PATH I168
J 0
(-8600 7125);
DISPLAY 0.978723 (-8600 7125);
PAINT WHITE (-8600 7125);
DISPLAY INVISIBLE (-8600 7125);
FORCEPROP 1 LAST PART_NUMBER CS00002JB13
J 0
(-8610 6825);
DISPLAY 0.510638 (-8610 6825);
DISPLAY INVISIBLE (-8610 6825);
FORCEADD Q_RES..1
(-9375 7125);
FORCEPROP 1 LAST LOCATION PR6817
J 0
(-9625 7125);
DISPLAY 0.638298 (-9625 7125);
FORCEPROP 2 LAST SEC 1
J 0
(-9425 7325);
DISPLAY 0.680851 (-9425 7325);
PAINT MONO (-9425 7325);
DISPLAY INVISIBLE (-9425 7325);
FORCEPROP 1 LASTPIN (-9475 7125) $PN 1
J 0
(-9463 7137);
DISPLAY 0.787234 (-9463 7137);
PAINT MONO (-9463 7137);
FORCEPROP 1 LASTPIN (-9275 7125) $PN 2
J 0
(-9313 7137);
DISPLAY 0.787234 (-9313 7137);
PAINT MONO (-9313 7137);
FORCEPROP 1 LAST MATERIAL EMPTY
J 0
(-9425 7150);
DISPLAY 0.510638 (-9425 7150);
FORCEPROP 1 LAST VALUE 1K
J 2
(-9150 7125);
DISPLAY 0.510638 (-9150 7125);
FORCEPROP 1 LAST TOLERANCE 1%
J 0
(-9100 7125);
DISPLAY 0.510638 (-9100 7125);
FORCEPROP 2 LAST CDS_LIB pure_quanta
J 0
(-9375 7125);
DISPLAY INVISIBLE (-9375 7125);
FORCEPROP 2 LAST SEC_TYPE 0402LF
J 0
(-9425 7325);
DISPLAY 1.021277 (-9425 7325);
DISPLAY INVISIBLE (-9425 7325);
FORCEPROP 1 LAST WATTAGE 1/16W
J 2
(-9200 7275);
DISPLAY 0.510638 (-9200 7275);
DISPLAY INVISIBLE (-9200 7275);
FORCEPROP 1 LAST PACK_TYPE 0402LF
J 0
(-9150 7275);
DISPLAY 0.510638 (-9150 7275);
DISPLAY INVISIBLE (-9150 7275);
FORCEPROP 1 LAST PATH I169
J 0
(-9425 7275);
DISPLAY 0.978723 (-9425 7275);
PAINT WHITE (-9425 7275);
DISPLAY INVISIBLE (-9425 7275);
FORCEPROP 1 LAST PART_NUMBER CS21002FB06
J 0
(-9475 7225);
DISPLAY 0.510638 (-9475 7225);
DISPLAY INVISIBLE (-9475 7225);
FORCEADD OFFPAGE..6
(-11075 6575);
FORCEPROP 2 LAST $XR0 151 
J 0
(-11355 6575);
DISPLAY 0.638298 (-11355 6575);
PAINT MONO (-11355 6575);
FORCEPROP 2 LAST CDS_LIB standard
J 0
(-11075 6575);
DISPLAY INVISIBLE (-11075 6575);
FORCEPROP 1 LAST OFFPAGE TRUE
J 0
(-10750 6450);
DISPLAY 0.872340 (-10750 6450);
PAINT GREEN (-10750 6450);
DISPLAY INVISIBLE (-10750 6450);
FORCEPROP 1 LAST COMMENT_BODY TRUE
J 0
(-10975 6500);
DISPLAY 0.872340 (-10975 6500);
PAINT GREEN (-10975 6500);
DISPLAY INVISIBLE (-10975 6500);
FORCEPROP 2 LAST PATH I17
J 0
(-11350 6625);
DISPLAY 1.021277 (-11350 6625);
DISPLAY INVISIBLE (-11350 6625);
FORCEADD UNIVERSAL_GND..1
(-7800 4350);
FORCEPROP 3 LASTPIN (-7800 4400) SIG_NAME GND\g
J 0
(-7790 4410);
DISPLAY 0.659574 (-7790 4410);
PAINT MONO (-7790 4410);
DISPLAY INVISIBLE (-7790 4410);
FORCEPROP 2 LAST CDS_LIB pure_quanta_power
J 0
(-7800 4350);
DISPLAY INVISIBLE (-7800 4350);
FORCEPROP 1 LAST HDL_POWER GND
J 1
(-7775 4275);
DISPLAY 0.872340 (-7775 4275);
PAINT GREEN (-7775 4275);
DISPLAY INVISIBLE (-7775 4275);
FORCEPROP 1 LAST PATH I172
J 0
(-7725 4350);
DISPLAY 0.872340 (-7725 4350);
PAINT AQUA (-7725 4350);
DISPLAY INVISIBLE (-7725 4350);
FORCEADD VCC15..1
(-9800 2450);
FORCEPROP 3 LASTPIN (-9800 2400) SIG_NAME P5V_AUX\g
J 0
(-9790 2410);
DISPLAY 0.659574 (-9790 2410);
PAINT MONO (-9790 2410);
DISPLAY INVISIBLE (-9790 2410);
FORCEPROP 1 LAST HDL_POWER P5V_AUX
J 1
(-9800 2500);
DISPLAY 0.617021 (-9800 2500);
PAINT GREEN (-9800 2500);
FORCEPROP 2 LAST CDS_LIB pure_quanta_power
J 0
(-9800 2450);
DISPLAY INVISIBLE (-9800 2450);
FORCEPROP 1 LAST PATH I176
J 0
(-9750 2475);
DISPLAY 0.872340 (-9750 2475);
PAINT AQUA (-9750 2475);
DISPLAY INVISIBLE (-9750 2475);
FORCEADD Q_RES..1
(-9500 2300);
FORCEPROP 1 LAST LOCATION PR6604
J 0
(-9700 2300);
DISPLAY 0.787234 (-9700 2300);
FORCEPROP 2 LAST SEC 1
J 0
(-9550 2500);
DISPLAY 0.680851 (-9550 2500);
PAINT MONO (-9550 2500);
DISPLAY INVISIBLE (-9550 2500);
FORCEPROP 1 LASTPIN (-9600 2300) $PN 1
J 0
(-9588 2312);
DISPLAY 0.787234 (-9588 2312);
PAINT MONO (-9588 2312);
FORCEPROP 1 LASTPIN (-9400 2300) $PN 2
J 0
(-9438 2312);
DISPLAY 0.787234 (-9438 2312);
PAINT MONO (-9438 2312);
FORCEPROP 1 LAST VALUE 5.36K
J 2
(-9200 2300);
DISPLAY 0.510638 (-9200 2300);
FORCEPROP 1 LAST WATTAGE 1/16W
J 2
(-9325 2250);
DISPLAY 0.510638 (-9325 2250);
FORCEPROP 1 LAST TOLERANCE 1%
J 0
(-9175 2300);
DISPLAY 0.510638 (-9175 2300);
FORCEPROP 1 LAST MATERIAL EMPTY
J 0
(-9600 2250);
DISPLAY 0.510638 (-9600 2250);
FORCEPROP 1 LAST PACK_TYPE 0402LF
J 0
(-9275 2250);
DISPLAY 0.510638 (-9275 2250);
FORCEPROP 2 LAST SEC_TYPE 0402LF
J 0
(-9550 2500);
DISPLAY 1.021277 (-9550 2500);
DISPLAY INVISIBLE (-9550 2500);
FORCEPROP 2 LAST CDS_LIB pure_quanta
J 0
(-9500 2300);
DISPLAY INVISIBLE (-9500 2300);
FORCEPROP 1 LAST PATH I178
J 0
(-9550 2450);
DISPLAY 0.978723 (-9550 2450);
PAINT WHITE (-9550 2450);
DISPLAY INVISIBLE (-9550 2450);
FORCEPROP 1 LAST PART_NUMBER CS25362FB02
J 0
(-9600 2200);
DISPLAY 0.510638 (-9600 2200);
DISPLAY INVISIBLE (-9600 2200);
FORCEADD Q_RES..1
(-8550 2775);
FORCEPROP 1 LAST LOCATION PR6603
J 0
(-8800 2775);
DISPLAY 0.787234 (-8800 2775);
FORCEPROP 2 LAST SEC 1
J 0
(-8600 2975);
DISPLAY 0.680851 (-8600 2975);
PAINT MONO (-8600 2975);
DISPLAY INVISIBLE (-8600 2975);
FORCEPROP 1 LASTPIN (-8650 2775) $PN 1
J 0
(-8638 2787);
DISPLAY 0.787234 (-8638 2787);
PAINT MONO (-8638 2787);
FORCEPROP 1 LASTPIN (-8450 2775) $PN 2
J 0
(-8488 2787);
DISPLAY 0.787234 (-8488 2787);
PAINT MONO (-8488 2787);
FORCEPROP 1 LAST TOLERANCE 5%
J 0
(-8525 2700);
DISPLAY 0.638298 (-8525 2700);
FORCEPROP 1 LAST VALUE 0
J 2
(-8575 2700);
DISPLAY 0.638298 (-8575 2700);
FORCEPROP 2 LAST SEC_TYPE 0402LF
J 0
(-8600 2975);
DISPLAY 1.021277 (-8600 2975);
DISPLAY INVISIBLE (-8600 2975);
FORCEPROP 1 LAST PACK_TYPE 0402LF
J 0
(-8400 2900);
DISPLAY 0.510638 (-8400 2900);
DISPLAY INVISIBLE (-8400 2900);
FORCEPROP 2 LAST CDS_LIB pure_quanta
J 0
(-8550 2775);
DISPLAY INVISIBLE (-8550 2775);
FORCEPROP 1 LAST MATERIAL CHIP
J 0
(-8675 2900);
DISPLAY 0.510638 (-8675 2900);
DISPLAY INVISIBLE (-8675 2900);
FORCEPROP 1 LAST WATTAGE 1/16W
J 2
(-8425 2900);
DISPLAY 0.510638 (-8425 2900);
DISPLAY INVISIBLE (-8425 2900);
FORCEPROP 1 LAST PATH I183
J 0
(-8600 2925);
DISPLAY 0.978723 (-8600 2925);
PAINT WHITE (-8600 2925);
DISPLAY INVISIBLE (-8600 2925);
FORCEPROP 1 LAST PART_NUMBER CS00002JB13
J 0
(-8675 2850);
DISPLAY 0.510638 (-8675 2850);
DISPLAY INVISIBLE (-8675 2850);
FORCEADD OFFPAGE..2
(-4975 6425);
FORCEPROP 2 LAST $XR0 364 
J 0
(-4786 6425);
DISPLAY 0.638298 (-4786 6425);
PAINT MONO (-4786 6425);
FORCEPROP 2 LAST CDS_LIB standard
J 0
(-4975 6425);
DISPLAY INVISIBLE (-4975 6425);
FORCEPROP 1 LAST OFFPAGE TRUE
J 0
(-4650 6300);
DISPLAY 0.872340 (-4650 6300);
PAINT GREEN (-4650 6300);
DISPLAY INVISIBLE (-4650 6300);
FORCEPROP 1 LAST COMMENT_BODY TRUE
J 0
(-5020 6330);
DISPLAY 0.872340 (-5020 6330);
PAINT GREEN (-5020 6330);
DISPLAY INVISIBLE (-5020 6330);
FORCEPROP 2 LAST PATH I186
J 0
(-4800 6500);
DISPLAY 0.680851 (-4800 6500);
DISPLAY INVISIBLE (-4800 6500);
FORCEADD OFFPAGE..4
(-4975 6325);
FORCEPROP 2 LAST $XR0 364 
J 0
(-4789 6325);
DISPLAY 0.638298 (-4789 6325);
PAINT MONO (-4789 6325);
FORCEPROP 2 LAST CDS_LIB standard
J 0
(-4975 6325);
DISPLAY INVISIBLE (-4975 6325);
FORCEPROP 1 LAST OFFPAGE TRUE
J 0
(-4650 6200);
DISPLAY 0.872340 (-4650 6200);
PAINT GREEN (-4650 6200);
DISPLAY INVISIBLE (-4650 6200);
FORCEPROP 1 LAST COMMENT_BODY TRUE
J 0
(-5000 6225);
DISPLAY 0.872340 (-5000 6225);
PAINT GREEN (-5000 6225);
DISPLAY INVISIBLE (-5000 6225);
FORCEPROP 2 LAST PATH I187
J 0
(-4800 6400);
DISPLAY 0.680851 (-4800 6400);
DISPLAY INVISIBLE (-4800 6400);
FORCEADD Q_RES..1
(-4800 5875);
FORCEPROP 1 LAST LOCATION PR6609
J 0
(-4850 5925);
DISPLAY 0.978723 (-4850 5925);
FORCEPROP 0 LAST $SEC 1
J 0
(-4850 5975);
DISPLAY 0.680851 (-4850 5975);
PAINT MONO (-4850 5975);
DISPLAY INVISIBLE (-4850 5975);
FORCEPROP 0 LAST CDS_SEC 1
J 0
(-4850 5975);
DISPLAY 0.680851 (-4850 5975);
DISPLAY INVISIBLE (-4850 5975);
FORCEPROP 1 LASTPIN (-4900 5875) $PN 1
J 0
(-4888 5887);
DISPLAY 0.787234 (-4888 5887);
PAINT MONO (-4888 5887);
FORCEPROP 1 LASTPIN (-4700 5875) $PN 2
J 0
(-4735 5885);
DISPLAY 0.787234 (-4735 5885);
PAINT MONO (-4735 5885);
FORCEPROP 1 LAST TOLERANCE 5%
J 0
(-4600 5900);
DISPLAY 0.510638 (-4600 5900);
FORCEPROP 1 LAST VALUE 0
J 2
(-4625 5900);
DISPLAY 0.510638 (-4625 5900);
FORCEPROP 1 LAST MATERIAL CHIP
J 0
(-5175 5800);
DISPLAY 0.510638 (-5175 5800);
FORCEPROP 1 LAST WATTAGE 1/16W
J 2
(-4925 5800);
DISPLAY 0.510638 (-4925 5800);
FORCEPROP 2 LAST CDS_LIB pure_quanta
J 0
(-4800 5875);
DISPLAY INVISIBLE (-4800 5875);
FORCEPROP 1 LAST PACK_TYPE 0402LF
J 0
(-4650 6000);
DISPLAY 0.510638 (-4650 6000);
DISPLAY INVISIBLE (-4650 6000);
FORCEPROP 1 LAST PATH I188
J 0
(-4850 6025);
DISPLAY 0.978723 (-4850 6025);
PAINT WHITE (-4850 6025);
DISPLAY INVISIBLE (-4850 6025);
FORCEPROP 1 LAST PART_NUMBER CS00002JB13
J 0
(-4900 5800);
DISPLAY 0.510638 (-4900 5800);
DISPLAY INVISIBLE (-4900 5800);
FORCEADD UNIVERSAL_GND..1
(-4475 5725);
FORCEPROP 3 LASTPIN (-4475 5775) SIG_NAME GND\g
J 0
(-4465 5785);
DISPLAY 0.659574 (-4465 5785);
PAINT MONO (-4465 5785);
DISPLAY INVISIBLE (-4465 5785);
FORCEPROP 2 LAST CDS_LIB pure_quanta_power
J 0
(-4475 5725);
DISPLAY INVISIBLE (-4475 5725);
FORCEPROP 1 LAST HDL_POWER GND
J 1
(-4450 5650);
DISPLAY 0.872340 (-4450 5650);
PAINT GREEN (-4450 5650);
DISPLAY INVISIBLE (-4450 5650);
FORCEPROP 1 LAST PATH I189
J 0
(-4400 5725);
DISPLAY 0.872340 (-4400 5725);
PAINT AQUA (-4400 5725);
DISPLAY INVISIBLE (-4400 5725);
FORCEADD Q_RES..1
(-4800 5425);
FORCEPROP 1 LAST LOCATION PR6610
J 0
(-4850 5475);
DISPLAY 0.978723 (-4850 5475);
FORCEPROP 0 LAST $SEC 1
J 0
(-4850 5525);
DISPLAY 0.680851 (-4850 5525);
PAINT MONO (-4850 5525);
DISPLAY INVISIBLE (-4850 5525);
FORCEPROP 0 LAST CDS_SEC 1
J 0
(-4850 5525);
DISPLAY 0.680851 (-4850 5525);
DISPLAY INVISIBLE (-4850 5525);
FORCEPROP 1 LASTPIN (-4900 5425) $PN 1
J 0
(-4888 5437);
DISPLAY 0.787234 (-4888 5437);
PAINT MONO (-4888 5437);
FORCEPROP 1 LASTPIN (-4700 5425) $PN 2
J 0
(-4738 5437);
DISPLAY 0.787234 (-4738 5437);
PAINT MONO (-4738 5437);
FORCEPROP 1 LAST MATERIAL CHIP
J 0
(-5175 5350);
DISPLAY 0.510638 (-5175 5350);
FORCEPROP 1 LAST WATTAGE 1/16W
J 2
(-4925 5350);
DISPLAY 0.510638 (-4925 5350);
FORCEPROP 1 LAST TOLERANCE 5%
J 0
(-4625 5450);
DISPLAY 0.510638 (-4625 5450);
FORCEPROP 1 LAST VALUE 0
J 2
(-4650 5450);
DISPLAY 0.510638 (-4650 5450);
FORCEPROP 2 LAST CDS_LIB pure_quanta
J 0
(-4800 5425);
DISPLAY INVISIBLE (-4800 5425);
FORCEPROP 1 LAST PACK_TYPE 0402LF
J 0
(-4650 5550);
DISPLAY 0.510638 (-4650 5550);
DISPLAY INVISIBLE (-4650 5550);
FORCEPROP 1 LAST PATH I190
J 0
(-4850 5575);
DISPLAY 0.978723 (-4850 5575);
PAINT WHITE (-4850 5575);
DISPLAY INVISIBLE (-4850 5575);
FORCEPROP 1 LAST PART_NUMBER CS00002JB13
J 0
(-4900 5350);
DISPLAY 0.510638 (-4900 5350);
DISPLAY INVISIBLE (-4900 5350);
FORCEADD Q_RES..1
(-4775 4975);
FORCEPROP 1 LAST LOCATION PR6611
J 0
(-4825 5025);
DISPLAY 0.978723 (-4825 5025);
FORCEPROP 0 LAST $SEC 1
J 0
(-4825 5075);
DISPLAY 0.680851 (-4825 5075);
PAINT MONO (-4825 5075);
DISPLAY INVISIBLE (-4825 5075);
FORCEPROP 0 LAST CDS_SEC 1
J 0
(-4825 5075);
DISPLAY 0.680851 (-4825 5075);
DISPLAY INVISIBLE (-4825 5075);
FORCEPROP 1 LASTPIN (-4875 4975) $PN 1
J 0
(-4863 4987);
DISPLAY 0.787234 (-4863 4987);
PAINT MONO (-4863 4987);
FORCEPROP 1 LASTPIN (-4675 4975) $PN 2
J 0
(-4713 4987);
DISPLAY 0.787234 (-4713 4987);
PAINT MONO (-4713 4987);
FORCEPROP 1 LAST MATERIAL CHIP
J 0
(-5150 4900);
DISPLAY 0.510638 (-5150 4900);
FORCEPROP 1 LAST WATTAGE 1/16W
J 2
(-4900 4900);
DISPLAY 0.510638 (-4900 4900);
FORCEPROP 1 LAST TOLERANCE 5%
J 0
(-4600 5000);
DISPLAY 0.510638 (-4600 5000);
FORCEPROP 1 LAST VALUE 0
J 2
(-4625 5000);
DISPLAY 0.510638 (-4625 5000);
FORCEPROP 1 LAST PACK_TYPE 0402LF
J 0
(-4625 5100);
DISPLAY 0.510638 (-4625 5100);
DISPLAY INVISIBLE (-4625 5100);
FORCEPROP 2 LAST CDS_LIB pure_quanta
J 0
(-4775 4975);
DISPLAY INVISIBLE (-4775 4975);
FORCEPROP 1 LAST PATH I191
J 0
(-4825 5125);
DISPLAY 0.978723 (-4825 5125);
PAINT WHITE (-4825 5125);
DISPLAY INVISIBLE (-4825 5125);
FORCEPROP 1 LAST PART_NUMBER CS00002JB13
J 0
(-4875 4900);
DISPLAY 0.510638 (-4875 4900);
DISPLAY INVISIBLE (-4875 4900);
FORCEADD Q_RES..1
(-4775 4525);
FORCEPROP 1 LAST LOCATION PR6612
J 0
(-4825 4575);
DISPLAY 0.978723 (-4825 4575);
FORCEPROP 0 LAST $SEC 1
J 0
(-4825 4625);
DISPLAY 0.680851 (-4825 4625);
PAINT MONO (-4825 4625);
DISPLAY INVISIBLE (-4825 4625);
FORCEPROP 0 LAST CDS_SEC 1
J 0
(-4825 4625);
DISPLAY 0.680851 (-4825 4625);
DISPLAY INVISIBLE (-4825 4625);
FORCEPROP 1 LASTPIN (-4875 4525) $PN 1
J 0
(-4863 4537);
DISPLAY 0.787234 (-4863 4537);
PAINT MONO (-4863 4537);
FORCEPROP 1 LASTPIN (-4675 4525) $PN 2
J 0
(-4713 4537);
DISPLAY 0.787234 (-4713 4537);
PAINT MONO (-4713 4537);
FORCEPROP 1 LAST WATTAGE 1/16W
J 2
(-4900 4450);
DISPLAY 0.510638 (-4900 4450);
FORCEPROP 1 LAST MATERIAL CHIP
J 0
(-5150 4450);
DISPLAY 0.510638 (-5150 4450);
FORCEPROP 1 LAST TOLERANCE 5%
J 0
(-4600 4550);
DISPLAY 0.510638 (-4600 4550);
FORCEPROP 1 LAST VALUE 0
J 2
(-4625 4550);
DISPLAY 0.510638 (-4625 4550);
FORCEPROP 1 LAST PACK_TYPE 0402LF
J 0
(-4625 4650);
DISPLAY 0.510638 (-4625 4650);
DISPLAY INVISIBLE (-4625 4650);
FORCEPROP 2 LAST CDS_LIB pure_quanta
J 0
(-4775 4525);
DISPLAY INVISIBLE (-4775 4525);
FORCEPROP 1 LAST PATH I192
J 0
(-4825 4675);
DISPLAY 0.978723 (-4825 4675);
PAINT WHITE (-4825 4675);
DISPLAY INVISIBLE (-4825 4675);
FORCEPROP 1 LAST PART_NUMBER CS00002JB13
J 0
(-4875 4450);
DISPLAY 0.510638 (-4875 4450);
DISPLAY INVISIBLE (-4875 4450);
FORCEADD Q_RES..1
(-4775 4075);
FORCEPROP 1 LAST LOCATION PR6613
J 0
(-4825 4125);
DISPLAY 0.978723 (-4825 4125);
FORCEPROP 0 LAST $SEC 1
J 0
(-4825 4175);
DISPLAY 0.680851 (-4825 4175);
PAINT MONO (-4825 4175);
DISPLAY INVISIBLE (-4825 4175);
FORCEPROP 0 LAST CDS_SEC 1
J 0
(-4825 4175);
DISPLAY 0.680851 (-4825 4175);
DISPLAY INVISIBLE (-4825 4175);
FORCEPROP 1 LASTPIN (-4875 4075) $PN 1
J 0
(-4863 4087);
DISPLAY 0.787234 (-4863 4087);
PAINT MONO (-4863 4087);
FORCEPROP 1 LASTPIN (-4675 4075) $PN 2
J 0
(-4713 4087);
DISPLAY 0.787234 (-4713 4087);
PAINT MONO (-4713 4087);
FORCEPROP 1 LAST MATERIAL CHIP
J 0
(-5150 4000);
DISPLAY 0.510638 (-5150 4000);
FORCEPROP 1 LAST TOLERANCE 5%
J 0
(-4600 4100);
DISPLAY 0.510638 (-4600 4100);
FORCEPROP 1 LAST VALUE 0
J 2
(-4625 4100);
DISPLAY 0.510638 (-4625 4100);
FORCEPROP 1 LAST WATTAGE 1/16W
J 2
(-4900 4000);
DISPLAY 0.510638 (-4900 4000);
FORCEPROP 2 LAST CDS_LIB pure_quanta
J 0
(-4775 4075);
DISPLAY INVISIBLE (-4775 4075);
FORCEPROP 1 LAST PACK_TYPE 0402LF
J 0
(-4625 4200);
DISPLAY 0.510638 (-4625 4200);
DISPLAY INVISIBLE (-4625 4200);
FORCEPROP 1 LAST PATH I193
J 0
(-4825 4225);
DISPLAY 0.978723 (-4825 4225);
PAINT WHITE (-4825 4225);
DISPLAY INVISIBLE (-4825 4225);
FORCEPROP 1 LAST PART_NUMBER CS00002JB13
J 0
(-4875 4000);
DISPLAY 0.510638 (-4875 4000);
DISPLAY INVISIBLE (-4875 4000);
FORCEADD UNIVERSAL_GND..1
(-4450 5225);
FORCEPROP 3 LASTPIN (-4450 5275) SIG_NAME GND\g
J 0
(-4440 5285);
DISPLAY 0.659574 (-4440 5285);
PAINT MONO (-4440 5285);
DISPLAY INVISIBLE (-4440 5285);
FORCEPROP 2 LAST CDS_LIB pure_quanta_power
J 0
(-4450 5225);
DISPLAY INVISIBLE (-4450 5225);
FORCEPROP 1 LAST HDL_POWER GND
J 1
(-4425 5150);
DISPLAY 0.872340 (-4425 5150);
PAINT GREEN (-4425 5150);
DISPLAY INVISIBLE (-4425 5150);
FORCEPROP 1 LAST PATH I194
J 0
(-4375 5225);
DISPLAY 0.872340 (-4375 5225);
PAINT AQUA (-4375 5225);
DISPLAY INVISIBLE (-4375 5225);
FORCEADD UNIVERSAL_GND..1
(-4450 4750);
FORCEPROP 3 LASTPIN (-4450 4800) SIG_NAME GND\g
J 0
(-4440 4810);
DISPLAY 0.659574 (-4440 4810);
PAINT MONO (-4440 4810);
DISPLAY INVISIBLE (-4440 4810);
FORCEPROP 2 LAST CDS_LIB pure_quanta_power
J 0
(-4450 4750);
DISPLAY INVISIBLE (-4450 4750);
FORCEPROP 1 LAST HDL_POWER GND
J 1
(-4425 4675);
DISPLAY 0.872340 (-4425 4675);
PAINT GREEN (-4425 4675);
DISPLAY INVISIBLE (-4425 4675);
FORCEPROP 1 LAST PATH I195
J 0
(-4375 4750);
DISPLAY 0.872340 (-4375 4750);
PAINT AQUA (-4375 4750);
DISPLAY INVISIBLE (-4375 4750);
FORCEADD UNIVERSAL_GND..1
(-4425 4275);
FORCEPROP 3 LASTPIN (-4425 4325) SIG_NAME GND\g
J 0
(-4415 4335);
DISPLAY 0.659574 (-4415 4335);
PAINT MONO (-4415 4335);
DISPLAY INVISIBLE (-4415 4335);
FORCEPROP 2 LAST CDS_LIB pure_quanta_power
J 0
(-4425 4275);
DISPLAY INVISIBLE (-4425 4275);
FORCEPROP 1 LAST HDL_POWER GND
J 1
(-4400 4200);
DISPLAY 0.872340 (-4400 4200);
PAINT GREEN (-4400 4200);
DISPLAY INVISIBLE (-4400 4200);
FORCEPROP 1 LAST PATH I196
J 0
(-4350 4275);
DISPLAY 0.872340 (-4350 4275);
PAINT AQUA (-4350 4275);
DISPLAY INVISIBLE (-4350 4275);
FORCEADD UNIVERSAL_GND..1
(-4450 3850);
FORCEPROP 3 LASTPIN (-4450 3900) SIG_NAME GND\g
J 0
(-4440 3910);
DISPLAY 0.659574 (-4440 3910);
PAINT MONO (-4440 3910);
DISPLAY INVISIBLE (-4440 3910);
FORCEPROP 2 LAST CDS_LIB pure_quanta_power
J 0
(-4450 3850);
DISPLAY INVISIBLE (-4450 3850);
FORCEPROP 1 LAST HDL_POWER GND
J 1
(-4425 3775);
DISPLAY 0.872340 (-4425 3775);
PAINT GREEN (-4425 3775);
DISPLAY INVISIBLE (-4425 3775);
FORCEPROP 1 LAST PATH I197
J 0
(-4375 3850);
DISPLAY 0.872340 (-4375 3850);
PAINT AQUA (-4375 3850);
DISPLAY INVISIBLE (-4375 3850);
FORCEADD Q_RES..1
(-4825 3625);
FORCEPROP 1 LAST LOCATION PR6614
J 0
(-4875 3675);
DISPLAY 0.787234 (-4875 3675);
FORCEPROP 0 LAST $SEC 1
J 0
(-4875 3725);
DISPLAY 0.680851 (-4875 3725);
PAINT MONO (-4875 3725);
DISPLAY INVISIBLE (-4875 3725);
FORCEPROP 0 LAST CDS_SEC 1
J 0
(-4875 3725);
DISPLAY 0.680851 (-4875 3725);
DISPLAY INVISIBLE (-4875 3725);
FORCEPROP 1 LASTPIN (-4925 3625) $PN 1
J 0
(-4913 3637);
DISPLAY 0.787234 (-4913 3637);
PAINT MONO (-4913 3637);
FORCEPROP 1 LASTPIN (-4725 3625) $PN 2
J 0
(-4760 3635);
DISPLAY 0.787234 (-4760 3635);
PAINT MONO (-4760 3635);
FORCEPROP 1 LAST VALUE 0
J 2
(-4675 3650);
DISPLAY 0.510638 (-4675 3650);
FORCEPROP 1 LAST WATTAGE 1/16W
J 2
(-4950 3550);
DISPLAY 0.510638 (-4950 3550);
FORCEPROP 1 LAST TOLERANCE 5%
J 0
(-4625 3650);
DISPLAY 0.510638 (-4625 3650);
FORCEPROP 1 LAST MATERIAL CHIP
J 0
(-5200 3550);
DISPLAY 0.510638 (-5200 3550);
FORCEPROP 1 LAST PACK_TYPE 0402LF
J 0
(-4675 3750);
DISPLAY 0.510638 (-4675 3750);
DISPLAY INVISIBLE (-4675 3750);
FORCEPROP 2 LAST CDS_LIB pure_quanta
J 0
(-4825 3625);
DISPLAY INVISIBLE (-4825 3625);
FORCEPROP 1 LAST PATH I198
J 0
(-4875 3775);
DISPLAY 0.978723 (-4875 3775);
PAINT WHITE (-4875 3775);
DISPLAY INVISIBLE (-4875 3775);
FORCEPROP 1 LAST PART_NUMBER CS00002JB13
J 0
(-4925 3550);
DISPLAY 0.510638 (-4925 3550);
DISPLAY INVISIBLE (-4925 3550);
FORCEADD UNIVERSAL_GND..1
(-4375 3450);
FORCEPROP 3 LASTPIN (-4375 3500) SIG_NAME GND\g
J 0
(-4365 3510);
DISPLAY 0.659574 (-4365 3510);
PAINT MONO (-4365 3510);
DISPLAY INVISIBLE (-4365 3510);
FORCEPROP 2 LAST CDS_LIB pure_quanta_power
J 0
(-4375 3450);
DISPLAY INVISIBLE (-4375 3450);
FORCEPROP 1 LAST HDL_POWER GND
J 1
(-4350 3375);
DISPLAY 0.872340 (-4350 3375);
PAINT GREEN (-4350 3375);
DISPLAY INVISIBLE (-4350 3375);
FORCEPROP 1 LAST PATH I199
J 0
(-4300 3450);
DISPLAY 0.872340 (-4300 3450);
PAINT AQUA (-4300 3450);
DISPLAY INVISIBLE (-4300 3450);
FORCEADD UNIVERSAL_GND..1
(-8675 1800);
FORCEPROP 3 LASTPIN (-8675 1850) SIG_NAME GND\g
J 0
(-8665 1860);
DISPLAY 0.659574 (-8665 1860);
PAINT MONO (-8665 1860);
DISPLAY INVISIBLE (-8665 1860);
FORCEPROP 2 LAST CDS_LIB pure_quanta_power
J 0
(-8675 1800);
PAINT MONO (-8675 1800);
DISPLAY INVISIBLE (-8675 1800);
FORCEPROP 1 LAST HDL_POWER GND
J 1
(-8650 1725);
DISPLAY 0.872340 (-8650 1725);
PAINT GREEN (-8650 1725);
DISPLAY INVISIBLE (-8650 1725);
FORCEPROP 1 LAST PATH I2
J 0
(-8600 1800);
DISPLAY 0.872340 (-8600 1800);
PAINT AQUA (-8600 1800);
DISPLAY INVISIBLE (-8600 1800);
FORCEADD VCC15..1
(-10850 6175);
FORCEPROP 3 LASTPIN (-10850 6125) SIG_NAME P0V9_CPU0_RT_2D\g
J 0
(-10840 6135);
DISPLAY 0.659574 (-10840 6135);
PAINT MONO (-10840 6135);
DISPLAY INVISIBLE (-10840 6135);
FORCEPROP 1 LAST HDL_POWER P0V9_CPU0_RT_2D
J 1
(-10850 6225);
DISPLAY 0.617021 (-10850 6225);
PAINT GREEN (-10850 6225);
FORCEPROP 2 LAST CDS_LIB pure_quanta_power
J 0
(-10850 6175);
DISPLAY INVISIBLE (-10850 6175);
FORCEPROP 1 LAST PATH I200
J 0
(-10800 6200);
DISPLAY 0.872340 (-10800 6200);
PAINT AQUA (-10800 6200);
DISPLAY INVISIBLE (-10800 6200);
FORCEADD UNIVERSAL_GND..1
(-10850 5250);
FORCEPROP 3 LASTPIN (-10850 5300) SIG_NAME GND\g
J 0
(-10840 5310);
DISPLAY 0.659574 (-10840 5310);
PAINT MONO (-10840 5310);
DISPLAY INVISIBLE (-10840 5310);
FORCEPROP 2 LAST CDS_LIB pure_quanta_power
J 0
(-10850 5250);
DISPLAY INVISIBLE (-10850 5250);
FORCEPROP 1 LAST HDL_POWER GND
J 1
(-10825 5175);
DISPLAY 0.872340 (-10825 5175);
PAINT GREEN (-10825 5175);
DISPLAY INVISIBLE (-10825 5175);
FORCEPROP 1 LAST PATH I202
J 0
(-10775 5250);
DISPLAY 0.872340 (-10775 5250);
PAINT AQUA (-10775 5250);
DISPLAY INVISIBLE (-10775 5250);
FORCEADD UNIVERSAL_GND..1
(-7800 4575);
FORCEPROP 3 LASTPIN (-7800 4625) SIG_NAME GND\g
J 0
(-7790 4635);
DISPLAY 0.659574 (-7790 4635);
PAINT MONO (-7790 4635);
DISPLAY INVISIBLE (-7790 4635);
FORCEPROP 2 LAST CDS_LIB pure_quanta_power
J 0
(-7800 4575);
DISPLAY INVISIBLE (-7800 4575);
FORCEPROP 1 LAST HDL_POWER GND
J 1
(-7775 4500);
DISPLAY 0.872340 (-7775 4500);
PAINT GREEN (-7775 4500);
DISPLAY INVISIBLE (-7775 4500);
FORCEPROP 1 LAST PATH I203
J 0
(-7725 4575);
DISPLAY 0.872340 (-7725 4575);
PAINT AQUA (-7725 4575);
DISPLAY INVISIBLE (-7725 4575);
FORCEADD Q_RES..1
(-4825 2975);
FORCEPROP 1 LAST LOCATION PR6618
J 0
(-4875 3025);
DISPLAY 0.787234 (-4875 3025);
FORCEPROP 0 LAST $SEC 1
J 0
(-4875 3075);
DISPLAY 0.680851 (-4875 3075);
PAINT MONO (-4875 3075);
DISPLAY INVISIBLE (-4875 3075);
FORCEPROP 0 LAST CDS_SEC 1
J 0
(-4875 3075);
DISPLAY 0.680851 (-4875 3075);
DISPLAY INVISIBLE (-4875 3075);
FORCEPROP 1 LASTPIN (-4925 2975) $PN 1
J 0
(-4913 2987);
DISPLAY 0.787234 (-4913 2987);
PAINT MONO (-4913 2987);
FORCEPROP 1 LASTPIN (-4725 2975) $PN 2
J 0
(-4763 2987);
DISPLAY 0.787234 (-4763 2987);
PAINT MONO (-4763 2987);
FORCEPROP 1 LAST WATTAGE 1/16W
J 2
(-4950 2900);
DISPLAY 0.510638 (-4950 2900);
FORCEPROP 1 LAST MATERIAL CHIP
J 0
(-5200 2900);
DISPLAY 0.510638 (-5200 2900);
FORCEPROP 1 LAST VALUE 0
J 2
(-4675 3000);
DISPLAY 0.510638 (-4675 3000);
FORCEPROP 1 LAST TOLERANCE 5%
J 0
(-4625 3000);
DISPLAY 0.510638 (-4625 3000);
FORCEPROP 1 LAST PACK_TYPE 0402LF
J 0
(-4675 3100);
DISPLAY 0.510638 (-4675 3100);
DISPLAY INVISIBLE (-4675 3100);
FORCEPROP 2 LAST CDS_LIB pure_quanta
J 0
(-4825 2975);
DISPLAY INVISIBLE (-4825 2975);
FORCEPROP 1 LAST PATH I204
J 0
(-4875 3125);
DISPLAY 0.978723 (-4875 3125);
PAINT WHITE (-4875 3125);
DISPLAY INVISIBLE (-4875 3125);
FORCEPROP 1 LAST PART_NUMBER CS00002JB13
J 0
(-4925 2900);
DISPLAY 0.510638 (-4925 2900);
DISPLAY INVISIBLE (-4925 2900);
FORCEADD UNIVERSAL_GND..1
(-4550 2850);
FORCEPROP 3 LASTPIN (-4550 2900) SIG_NAME GND\g
J 0
(-4540 2910);
DISPLAY 0.659574 (-4540 2910);
PAINT MONO (-4540 2910);
DISPLAY INVISIBLE (-4540 2910);
FORCEPROP 2 LAST CDS_LIB pure_quanta_power
J 0
(-4550 2850);
DISPLAY INVISIBLE (-4550 2850);
FORCEPROP 1 LAST HDL_POWER GND
J 1
(-4525 2775);
DISPLAY 0.872340 (-4525 2775);
PAINT GREEN (-4525 2775);
DISPLAY INVISIBLE (-4525 2775);
FORCEPROP 1 LAST PATH I205
J 0
(-4475 2850);
DISPLAY 0.872340 (-4475 2850);
PAINT AQUA (-4475 2850);
DISPLAY INVISIBLE (-4475 2850);
FORCEADD Q_RES..1
(-9300 6425);
FORCEPROP 1 LAST LOCATION R649
J 0
(-9525 6425);
DISPLAY 0.638298 (-9525 6425);
FORCEPROP 0 LAST $SEC 1
J 0
(-9350 6475);
DISPLAY 0.680851 (-9350 6475);
PAINT MONO (-9350 6475);
DISPLAY INVISIBLE (-9350 6475);
FORCEPROP 0 LAST CDS_SEC 1
J 0
(-9350 6475);
DISPLAY 0.680851 (-9350 6475);
DISPLAY INVISIBLE (-9350 6475);
FORCEPROP 1 LASTPIN (-9400 6425) $PN 1
J 0
(-9388 6437);
DISPLAY 0.787234 (-9388 6437);
PAINT MONO (-9388 6437);
FORCEPROP 1 LASTPIN (-9200 6425) $PN 2
J 0
(-9238 6437);
DISPLAY 0.787234 (-9238 6437);
PAINT MONO (-9238 6437);
FORCEPROP 1 LAST MATERIAL EMPTY
J 0
(-9350 6450);
DISPLAY 0.510638 (-9350 6450);
FORCEPROP 1 LAST VALUE 4.7K
J 2
(-9075 6425);
DISPLAY 0.510638 (-9075 6425);
FORCEPROP 1 LAST TOLERANCE 1%
J 0
(-9025 6425);
DISPLAY 0.510638 (-9025 6425);
FORCEPROP 2 LAST CDS_LIB pure_quanta
J 0
(-9300 6425);
DISPLAY INVISIBLE (-9300 6425);
FORCEPROP 1 LAST PACK_TYPE 0402LF
J 0
(-9075 6575);
DISPLAY 0.510638 (-9075 6575);
DISPLAY INVISIBLE (-9075 6575);
FORCEPROP 1 LAST WATTAGE 1/16W
J 2
(-9125 6575);
DISPLAY 0.510638 (-9125 6575);
DISPLAY INVISIBLE (-9125 6575);
FORCEPROP 1 LAST PATH I207
J 0
(-9350 6575);
DISPLAY 0.978723 (-9350 6575);
PAINT WHITE (-9350 6575);
DISPLAY INVISIBLE (-9350 6575);
FORCEPROP 1 LAST PART_NUMBER CS24702FB06
J 0
(-9400 6525);
DISPLAY 0.510638 (-9400 6525);
DISPLAY INVISIBLE (-9400 6525);
FORCEADD Q_RES..2
R 2
(-10475 7450);
FORCEPROP 1 LAST LOCATION R6786
J 2
(-10530 7550);
DISPLAY 0.808511 (-10530 7550);
FORCEPROP 0 LAST $SEC 1
J 0
(-10525 7600);
DISPLAY 0.680851 (-10525 7600);
PAINT MONO (-10525 7600);
DISPLAY INVISIBLE (-10525 7600);
FORCEPROP 0 LAST CDS_SEC 1
J 0
(-10525 7600);
DISPLAY 0.680851 (-10525 7600);
DISPLAY INVISIBLE (-10525 7600);
FORCEPROP 1 LASTPIN (-10475 7550) $PN 1
J 2
(-10480 7512);
DISPLAY 0.787234 (-10480 7512);
PAINT MONO (-10480 7512);
FORCEPROP 1 LASTPIN (-10475 7350) $PN 2
J 2
(-10480 7360);
DISPLAY 0.787234 (-10480 7360);
PAINT MONO (-10480 7360);
FORCEPROP 1 LAST PACK_TYPE 0402LF
J 2
(-10525 7250);
DISPLAY 0.510638 (-10525 7250);
FORCEPROP 1 LAST TOLERANCE 1%
J 2
(-10530 7450);
DISPLAY 0.510638 (-10530 7450);
FORCEPROP 1 LAST VALUE 1K
J 2
(-10530 7500);
DISPLAY 0.510638 (-10530 7500);
FORCEPROP 1 LAST WATTAGE 1/16W
J 2
(-10525 7400);
DISPLAY 0.510638 (-10525 7400);
FORCEPROP 1 LAST MATERIAL CHIP
J 2
(-10525 7350);
DISPLAY 0.510638 (-10525 7350);
FORCEPROP 2 LAST CDS_LIB pure_quanta
J 0
(-10475 7450);
DISPLAY INVISIBLE (-10475 7450);
FORCEPROP 1 LAST PATH I208
J 2
(-10525 7625);
DISPLAY 0.978723 (-10525 7625);
PAINT WHITE (-10525 7625);
DISPLAY INVISIBLE (-10525 7625);
FORCEPROP 1 LAST PART_NUMBER CS21002FB06
J 2
(-10525 7300);
DISPLAY 0.510638 (-10525 7300);
DISPLAY INVISIBLE (-10525 7300);
FORCEADD UNIVERSAL_GND..1
(-10475 7150);
FORCEPROP 3 LASTPIN (-10475 7200) SIG_NAME GND\g
J 0
(-10465 7210);
DISPLAY 0.659574 (-10465 7210);
PAINT MONO (-10465 7210);
DISPLAY INVISIBLE (-10465 7210);
FORCEPROP 2 LAST CDS_LIB pure_quanta_power
J 0
(-10475 7150);
DISPLAY INVISIBLE (-10475 7150);
FORCEPROP 1 LAST HDL_POWER GND
J 1
(-10450 7075);
DISPLAY 0.872340 (-10450 7075);
PAINT GREEN (-10450 7075);
DISPLAY INVISIBLE (-10450 7075);
FORCEPROP 1 LAST PATH I209
J 0
(-10400 7150);
DISPLAY 0.872340 (-10400 7150);
PAINT AQUA (-10400 7150);
DISPLAY INVISIBLE (-10400 7150);
FORCEADD Q_RES..2
(-8300 6950);
FORCEPROP 1 LAST LOCATION PR883
J 0
(-8255 7075);
DISPLAY 0.638298 (-8255 7075);
FORCEPROP 0 LAST $SEC 1
J 0
(-8250 7125);
DISPLAY 0.680851 (-8250 7125);
PAINT MONO (-8250 7125);
DISPLAY INVISIBLE (-8250 7125);
FORCEPROP 0 LAST CDS_SEC 1
J 0
(-8250 7125);
DISPLAY 0.680851 (-8250 7125);
DISPLAY INVISIBLE (-8250 7125);
FORCEPROP 1 LASTPIN (-8300 7050) $PN 1
J 0
(-8295 7012);
DISPLAY 0.787234 (-8295 7012);
PAINT MONO (-8295 7012);
FORCEPROP 1 LASTPIN (-8300 6850) $PN 2
J 0
(-8295 6860);
DISPLAY 0.787234 (-8295 6860);
PAINT MONO (-8295 6860);
FORCEPROP 1 LAST MATERIAL EMPTY
J 0
(-8260 6875);
DISPLAY 0.510638 (-8260 6875);
FORCEPROP 1 LAST VALUE 0
J 0
(-8255 7025);
DISPLAY 0.510638 (-8255 7025);
FORCEPROP 1 LAST WATTAGE 1/16W
J 0
(-8260 6925);
DISPLAY 0.510638 (-8260 6925);
FORCEPROP 1 LAST TOLERANCE 5%
J 0
(-8255 6975);
DISPLAY 0.510638 (-8255 6975);
FORCEPROP 1 LAST PACK_TYPE 0402LF
J 0
(-8260 6775);
DISPLAY 0.510638 (-8260 6775);
FORCEPROP 2 LAST CDS_LIB pure_quanta
J 0
(-8300 6950);
DISPLAY INVISIBLE (-8300 6950);
FORCEPROP 1 LAST PATH I210
J 0
(-8250 7125);
DISPLAY 0.978723 (-8250 7125);
PAINT WHITE (-8250 7125);
DISPLAY INVISIBLE (-8250 7125);
FORCEPROP 1 LAST PART_NUMBER CS00002JB13
J 0
(-8260 6825);
DISPLAY 0.510638 (-8260 6825);
DISPLAY INVISIBLE (-8260 6825);
FORCEADD VCC15..1
(-10325 8150);
FORCEPROP 3 LASTPIN (-10325 8100) SIG_NAME P1V8_AUX\g
J 0
(-10315 8110);
DISPLAY 0.659574 (-10315 8110);
PAINT MONO (-10315 8110);
DISPLAY INVISIBLE (-10315 8110);
FORCEPROP 1 LAST HDL_POWER P1V8_AUX
J 1
(-10325 8200);
DISPLAY 0.617021 (-10325 8200);
PAINT GREEN (-10325 8200);
FORCEPROP 2 LAST CDS_LIB pure_quanta_power
J 0
(-10325 8150);
DISPLAY INVISIBLE (-10325 8150);
FORCEPROP 1 LAST PATH I211
J 0
(-10275 8175);
DISPLAY 0.872340 (-10275 8175);
PAINT AQUA (-10275 8175);
DISPLAY INVISIBLE (-10275 8175);
FORCEADD Q_RES..1
(-9150 8025);
FORCEPROP 1 LAST LOCATION R643
J 0
(-9400 8025);
DISPLAY 0.638298 (-9400 8025);
FORCEPROP 0 LAST $SEC 1
J 0
(-8925 8200);
DISPLAY 0.680851 (-8925 8200);
PAINT MONO (-8925 8200);
DISPLAY INVISIBLE (-8925 8200);
FORCEPROP 0 LAST CDS_SEC 1
J 0
(-8925 8200);
DISPLAY 0.680851 (-8925 8200);
DISPLAY INVISIBLE (-8925 8200);
FORCEPROP 1 LASTPIN (-9250 8025) $PN 1
J 0
(-9238 8037);
DISPLAY 0.787234 (-9238 8037);
PAINT MONO (-9238 8037);
FORCEPROP 1 LASTPIN (-9050 8025) $PN 2
J 0
(-9088 8037);
DISPLAY 0.787234 (-9088 8037);
PAINT MONO (-9088 8037);
FORCEPROP 1 LAST TOLERANCE 1%
J 0
(-8875 8025);
DISPLAY 0.510638 (-8875 8025);
FORCEPROP 1 LAST MATERIAL EMPTY
J 0
(-9250 8175);
DISPLAY 0.510638 (-9250 8175);
FORCEPROP 1 LAST WATTAGE 1/16W
J 2
(-8975 8175);
DISPLAY 0.510638 (-8975 8175);
FORCEPROP 1 LAST PACK_TYPE 0402LF
J 0
(-8925 8175);
DISPLAY 0.510638 (-8925 8175);
FORCEPROP 1 LAST VALUE 1K
J 2
(-8925 8025);
DISPLAY 0.510638 (-8925 8025);
FORCEPROP 2 LAST CDS_LIB pure_quanta
J 0
(-9150 8025);
DISPLAY INVISIBLE (-9150 8025);
FORCEPROP 1 LAST PATH I212
J 0
(-9200 8175);
DISPLAY 0.978723 (-9200 8175);
PAINT WHITE (-9200 8175);
DISPLAY INVISIBLE (-9200 8175);
FORCEPROP 1 LAST PART_NUMBER CS21002FB06
J 0
(-9250 8125);
DISPLAY 0.510638 (-9250 8125);
DISPLAY INVISIBLE (-9250 8125);
FORCEADD Q_RES..1
(-9950 8050);
FORCEPROP 1 LAST LOCATION R6860
J 0
(-10225 8050);
DISPLAY 0.638298 (-10225 8050);
FORCEPROP 0 LAST $SEC 1
J 0
(-9800 8175);
DISPLAY 0.680851 (-9800 8175);
PAINT MONO (-9800 8175);
DISPLAY INVISIBLE (-9800 8175);
FORCEPROP 0 LAST CDS_SEC 1
J 0
(-9800 8175);
DISPLAY 0.680851 (-9800 8175);
DISPLAY INVISIBLE (-9800 8175);
FORCEPROP 1 LASTPIN (-10050 8050) $PN 1
J 0
(-10038 8062);
DISPLAY 0.787234 (-10038 8062);
PAINT MONO (-10038 8062);
FORCEPROP 1 LASTPIN (-9850 8050) $PN 2
J 0
(-9888 8062);
DISPLAY 0.787234 (-9888 8062);
PAINT MONO (-9888 8062);
FORCEPROP 1 LAST PACK_TYPE 0402LF
J 0
(-9800 8150);
DISPLAY 0.510638 (-9800 8150);
FORCEPROP 1 LAST MATERIAL CHIP
J 0
(-10075 8150);
DISPLAY 0.510638 (-10075 8150);
FORCEPROP 1 LAST VALUE 1K
J 2
(-9725 8050);
DISPLAY 0.510638 (-9725 8050);
FORCEPROP 1 LAST TOLERANCE 1%
J 0
(-9675 8050);
DISPLAY 0.510638 (-9675 8050);
FORCEPROP 1 LAST WATTAGE 1/16W
J 2
(-9825 8150);
DISPLAY 0.510638 (-9825 8150);
FORCEPROP 2 LAST CDS_LIB pure_quanta
J 0
(-9950 8050);
DISPLAY INVISIBLE (-9950 8050);
FORCEPROP 1 LAST PATH I213
J 0
(-10000 8200);
DISPLAY 0.978723 (-10000 8200);
PAINT WHITE (-10000 8200);
DISPLAY INVISIBLE (-10000 8200);
FORCEPROP 1 LAST PART_NUMBER CS21002FB06
J 0
(-10075 8100);
DISPLAY 0.510638 (-10075 8100);
DISPLAY INVISIBLE (-10075 8100);
FORCEADD Q_SHORT..1
(-10550 5875);
FORCEPROP 1 LAST LOCATION PJ09_P0_P
J 0
(-10625 5930);
DISPLAY 0.723404 (-10625 5930);
PAINT GREEN (-10625 5930);
FORCEPROP 2 LAST SEC 1
J 0
(-10625 6125);
DISPLAY 0.680851 (-10625 6125);
PAINT MONO (-10625 6125);
DISPLAY INVISIBLE (-10625 6125);
FORCEPROP 2 LASTPIN (-10675 5875) $PN 1
J 2
(-10685 5885);
DISPLAY 0.680851 (-10685 5885);
PAINT MONO (-10685 5885);
FORCEPROP 2 LASTPIN (-10425 5875) $PN 2
J 0
(-10415 5885);
DISPLAY 0.680851 (-10415 5885);
PAINT MONO (-10415 5885);
FORCEPROP 1 LAST MATERIAL EMPTY
J 0
(-10625 6035);
DISPLAY 0.723404 (-10625 6035);
PAINT GREEN (-10625 6035);
FORCEPROP 2 LAST PACK_TYPE SM
J 0
(-10625 6075);
DISPLAY 0.680851 (-10625 6075);
FORCEPROP 2 LAST CDS_LIB pure_quanta
J 0
(-10550 5875);
DISPLAY INVISIBLE (-10550 5875);
FORCEPROP 1 LAST NEEDS_NO_SIZE TRUE
J 0
(-10550 5875);
DISPLAY 0.468085 (-10550 5875);
PAINT GREEN (-10550 5875);
DISPLAY INVISIBLE (-10550 5875);
FORCEPROP 2 LAST SEC_TYPE SM
J 0
(-10625 6125);
DISPLAY 0.680851 (-10625 6125);
DISPLAY INVISIBLE (-10625 6125);
FORCEPROP 1 LAST PATH I214
J 0
(-10625 6080);
DISPLAY 0.723404 (-10625 6080);
PAINT GREEN (-10625 6080);
DISPLAY INVISIBLE (-10625 6080);
FORCEPROP 1 LAST PART_NUMBER SHORT16
J 0
(-10625 5985);
DISPLAY 0.723404 (-10625 5985);
PAINT GREEN (-10625 5985);
DISPLAY INVISIBLE (-10625 5985);
FORCEADD Q_SHORT..1
(-10550 5500);
FORCEPROP 1 LAST LOCATION PJ09_P0_N
J 0
(-10625 5555);
DISPLAY 0.723404 (-10625 5555);
PAINT GREEN (-10625 5555);
FORCEPROP 2 LAST SEC 1
J 0
(-10625 5750);
DISPLAY 0.680851 (-10625 5750);
PAINT MONO (-10625 5750);
DISPLAY INVISIBLE (-10625 5750);
FORCEPROP 2 LASTPIN (-10675 5500) $PN 1
J 2
(-10685 5510);
DISPLAY 0.680851 (-10685 5510);
PAINT MONO (-10685 5510);
FORCEPROP 2 LASTPIN (-10425 5500) $PN 2
J 0
(-10415 5510);
DISPLAY 0.680851 (-10415 5510);
PAINT MONO (-10415 5510);
FORCEPROP 1 LAST MATERIAL EMPTY
J 0
(-10625 5660);
DISPLAY 0.723404 (-10625 5660);
PAINT GREEN (-10625 5660);
FORCEPROP 2 LAST PACK_TYPE SM
J 0
(-10625 5700);
DISPLAY 0.680851 (-10625 5700);
FORCEPROP 2 LAST SEC_TYPE SM
J 0
(-10625 5750);
DISPLAY 0.680851 (-10625 5750);
DISPLAY INVISIBLE (-10625 5750);
FORCEPROP 2 LAST CDS_LIB pure_quanta
J 0
(-10550 5500);
DISPLAY INVISIBLE (-10550 5500);
FORCEPROP 1 LAST NEEDS_NO_SIZE TRUE
J 0
(-10550 5500);
DISPLAY 0.468085 (-10550 5500);
PAINT GREEN (-10550 5500);
DISPLAY INVISIBLE (-10550 5500);
FORCEPROP 1 LAST PATH I215
J 0
(-10625 5705);
DISPLAY 0.723404 (-10625 5705);
PAINT GREEN (-10625 5705);
DISPLAY INVISIBLE (-10625 5705);
FORCEPROP 1 LAST PART_NUMBER SHORT16
J 0
(-10625 5610);
DISPLAY 0.723404 (-10625 5610);
PAINT GREEN (-10625 5610);
DISPLAY INVISIBLE (-10625 5610);
FORCEADD OFFPAGE..1
(-10650 7725);
FORCEPROP 2 LAST $XR0 81 
J 0
(-10901 7725);
DISPLAY 0.638298 (-10901 7725);
PAINT MONO (-10901 7725);
FORCEPROP 2 LAST CDS_LIB standard
J 0
(-10650 7725);
DISPLAY INVISIBLE (-10650 7725);
FORCEPROP 1 LAST OFFPAGE TRUE
J 0
(-10325 7600);
DISPLAY 0.872340 (-10325 7600);
PAINT GREEN (-10325 7600);
DISPLAY INVISIBLE (-10325 7600);
FORCEPROP 1 LAST COMMENT_BODY TRUE
J 0
(-10525 7625);
DISPLAY 0.872340 (-10525 7625);
PAINT GREEN (-10525 7625);
DISPLAY INVISIBLE (-10525 7625);
FORCEPROP 2 LAST PATH I23
J 0
(-10900 7775);
DISPLAY 1.021277 (-10900 7775);
DISPLAY INVISIBLE (-10900 7775);
FORCEADD OFFPAGE..5
(-11400 7875);
FORCEPROP 2 LAST $XR0 81 
J 0
(-11624 7875);
DISPLAY 0.638298 (-11624 7875);
PAINT MONO (-11624 7875);
FORCEPROP 2 LAST CDS_LIB standard
J 0
(-11400 7875);
DISPLAY INVISIBLE (-11400 7875);
FORCEPROP 1 LAST OFFPAGE TRUE
J 0
(-11075 7750);
DISPLAY 0.872340 (-11075 7750);
PAINT GREEN (-11075 7750);
DISPLAY INVISIBLE (-11075 7750);
FORCEPROP 1 LAST COMMENT_BODY TRUE
J 0
(-11300 7800);
DISPLAY 0.872340 (-11300 7800);
PAINT GREEN (-11300 7800);
DISPLAY INVISIBLE (-11300 7800);
FORCEPROP 2 LAST PATH I24
J 0
(-11675 7925);
DISPLAY 1.021277 (-11675 7925);
DISPLAY INVISIBLE (-11675 7925);
FORCEADD Q_RES..1
(-9975 5350);
FORCEPROP 1 LAST LOCATION PR6532
J 0
(-10225 5350);
DISPLAY 0.765957 (-10225 5350);
FORCEPROP 2 LAST $SEC 1
J 0
(-10025 5550);
DISPLAY 0.680851 (-10025 5550);
PAINT MONO (-10025 5550);
DISPLAY INVISIBLE (-10025 5550);
FORCEPROP 2 LAST CDS_SEC 1
J 0
(-10025 5550);
DISPLAY 1.021277 (-10025 5550);
DISPLAY INVISIBLE (-10025 5550);
FORCEPROP 1 LASTPIN (-10075 5350) $PN 1
J 0
(-10063 5362);
DISPLAY 0.617021 (-10063 5362);
PAINT WHITE (-10063 5362);
FORCEPROP 1 LASTPIN (-9875 5350) $PN 2
J 0
(-9913 5362);
DISPLAY 0.617021 (-9913 5362);
PAINT WHITE (-9913 5362);
FORCEPROP 1 LAST TOLERANCE 1%
J 0
(-9750 5350);
DISPLAY 0.617021 (-9750 5350);
FORCEPROP 1 LAST VALUE 49.9
J 2
(-9775 5350);
DISPLAY 0.617021 (-9775 5350);
FORCEPROP 1 LAST PACK_TYPE 0402LF
J 0
(-9675 5350);
DISPLAY 0.617021 (-9675 5350);
FORCEPROP 1 LAST MATERIAL CHIP
J 0
(-9850 5450);
DISPLAY 0.617021 (-9850 5450);
FORCEPROP 1 LAST WATTAGE 1/16W
J 2
(-9600 5450);
DISPLAY 0.617021 (-9600 5450);
FORCEPROP 2 LAST CDS_LIB pure_quanta
J 0
(-9975 5350);
PAINT MONO (-9975 5350);
DISPLAY INVISIBLE (-9975 5350);
FORCEPROP 1 LAST PATH I32
J 0
(-10025 5500);
DISPLAY 0.978723 (-10025 5500);
PAINT WHITE (-10025 5500);
DISPLAY INVISIBLE (-10025 5500);
FORCEPROP 1 LAST PART_NUMBER CS04992FB07
J 0
(-9850 5400);
DISPLAY 0.617021 (-9850 5400);
DISPLAY INVISIBLE (-9850 5400);
FORCEADD Q_RES..1
(-9925 6025);
FORCEPROP 1 LAST LOCATION PR6530
J 0
(-10225 6025);
DISPLAY 0.765957 (-10225 6025);
FORCEPROP 2 LAST $SEC 1
J 0
(-9975 6225);
DISPLAY 0.680851 (-9975 6225);
PAINT MONO (-9975 6225);
DISPLAY INVISIBLE (-9975 6225);
FORCEPROP 2 LAST CDS_SEC 1
J 0
(-9975 6225);
DISPLAY 1.021277 (-9975 6225);
DISPLAY INVISIBLE (-9975 6225);
FORCEPROP 1 LASTPIN (-10025 6025) $PN 1
J 0
(-10013 6037);
DISPLAY 0.617021 (-10013 6037);
PAINT WHITE (-10013 6037);
FORCEPROP 1 LASTPIN (-9825 6025) $PN 2
J 0
(-9863 6037);
DISPLAY 0.617021 (-9863 6037);
PAINT WHITE (-9863 6037);
FORCEPROP 1 LAST VALUE 49.9
J 2
(-9725 6025);
DISPLAY 0.617021 (-9725 6025);
FORCEPROP 1 LAST TOLERANCE 1%
J 0
(-9700 6025);
DISPLAY 0.617021 (-9700 6025);
FORCEPROP 1 LAST MATERIAL CHIP
J 0
(-9800 6125);
DISPLAY 0.617021 (-9800 6125);
FORCEPROP 1 LAST WATTAGE 1/16W
J 2
(-9550 6125);
DISPLAY 0.617021 (-9550 6125);
FORCEPROP 1 LAST PACK_TYPE 0402LF
J 0
(-9625 6025);
DISPLAY 0.617021 (-9625 6025);
FORCEPROP 2 LAST CDS_LIB pure_quanta
J 0
(-9925 6025);
PAINT MONO (-9925 6025);
DISPLAY INVISIBLE (-9925 6025);
FORCEPROP 1 LAST PATH I34
J 0
(-9975 6175);
DISPLAY 0.978723 (-9975 6175);
PAINT WHITE (-9975 6175);
DISPLAY INVISIBLE (-9975 6175);
FORCEPROP 1 LAST PART_NUMBER CS04992FB07
J 0
(-9800 6075);
DISPLAY 0.617021 (-9800 6075);
DISPLAY INVISIBLE (-9800 6075);
FORCEADD UNIVERSAL_GND..1
(-9450 5250);
FORCEPROP 3 LASTPIN (-9450 5300) SIG_NAME GND\g
J 0
(-9440 5310);
DISPLAY 0.659574 (-9440 5310);
PAINT MONO (-9440 5310);
DISPLAY INVISIBLE (-9440 5310);
FORCEPROP 2 LAST CDS_LIB pure_quanta_power
J 0
(-9450 5250);
PAINT MONO (-9450 5250);
DISPLAY INVISIBLE (-9450 5250);
FORCEPROP 1 LAST HDL_POWER GND
J 1
(-9425 5175);
DISPLAY 0.872340 (-9425 5175);
PAINT GREEN (-9425 5175);
DISPLAY INVISIBLE (-9425 5175);
FORCEPROP 1 LAST PATH I35
J 0
(-9375 5250);
DISPLAY 0.872340 (-9375 5250);
PAINT AQUA (-9375 5250);
DISPLAY INVISIBLE (-9375 5250);
FORCEADD VCC15..1
(-9425 6175);
FORCEPROP 3 LASTPIN (-9425 6125) SIG_NAME P0V9_CPU0_RT_2D\g
J 0
(-9415 6135);
DISPLAY 0.659574 (-9415 6135);
PAINT MONO (-9415 6135);
DISPLAY INVISIBLE (-9415 6135);
FORCEPROP 1 LAST HDL_POWER P0V9_CPU0_RT_2D
J 1
(-9425 6225);
DISPLAY 0.617021 (-9425 6225);
PAINT GREEN (-9425 6225);
FORCEPROP 2 LAST CDS_LIB pure_quanta_power
J 0
(-9425 6175);
DISPLAY INVISIBLE (-9425 6175);
FORCEPROP 1 LAST PATH I36
J 0
(-9375 6200);
DISPLAY 0.872340 (-9375 6200);
PAINT AQUA (-9375 6200);
DISPLAY INVISIBLE (-9375 6200);
FORCEADD VCC15..1
(-9100 4300);
FORCEPROP 3 LASTPIN (-9100 4250) SIG_NAME P3V3_AUX\g
J 0
(-9090 4260);
DISPLAY 0.659574 (-9090 4260);
PAINT MONO (-9090 4260);
DISPLAY INVISIBLE (-9090 4260);
FORCEPROP 1 LAST HDL_POWER P3V3_AUX
J 1
(-9100 4350);
DISPLAY 0.617021 (-9100 4350);
PAINT GREEN (-9100 4350);
FORCEPROP 2 LAST CDS_LIB pure_quanta_power
J 0
(-9100 4300);
DISPLAY INVISIBLE (-9100 4300);
FORCEPROP 1 LAST PATH I37
J 0
(-9050 4325);
DISPLAY 0.872340 (-9050 4325);
PAINT AQUA (-9050 4325);
DISPLAY INVISIBLE (-9050 4325);
FORCEADD UNIVERSAL_GND..1
(-7700 2200);
FORCEPROP 3 LASTPIN (-7700 2250) SIG_NAME GND\g
J 0
(-7690 2260);
DISPLAY 0.659574 (-7690 2260);
PAINT MONO (-7690 2260);
DISPLAY INVISIBLE (-7690 2260);
FORCEPROP 2 LAST CDS_LIB pure_quanta_power
J 0
(-7700 2200);
PAINT MONO (-7700 2200);
DISPLAY INVISIBLE (-7700 2200);
FORCEPROP 1 LAST HDL_POWER GND
J 1
(-7675 2125);
DISPLAY 0.872340 (-7675 2125);
PAINT GREEN (-7675 2125);
DISPLAY INVISIBLE (-7675 2125);
FORCEPROP 1 LAST PATH I41
J 0
(-7625 2200);
DISPLAY 0.872340 (-7625 2200);
PAINT AQUA (-7625 2200);
DISPLAY INVISIBLE (-7625 2200);
FORCEADD ISL69260IRAZT..1
(-6575 5125);
FORCEPROP 1 LAST LOCATION PU6502
J 0
(-7120 8177);
DISPLAY 0.617021 (-7120 8177);
PAINT GREEN (-7120 8177);
FORCEPROP 0 LAST SEC 1
J 0
(-7100 8225);
DISPLAY 0.680851 (-7100 8225);
PAINT MONO (-7100 8225);
DISPLAY INVISIBLE (-7100 8225);
FORCEPROP 0 LASTPIN (-7250 2775) $PN 34
J 2
(-7260 2785);
DISPLAY 0.680851 (-7260 2785);
PAINT MONO (-7260 2785);
FORCEPROP 0 LASTPIN (-7250 3875) $PN 33
J 2
(-7260 3885);
DISPLAY 0.680851 (-7260 3885);
PAINT MONO (-7260 3885);
FORCEPROP 0 LASTPIN (-5900 3625) $PN 30
J 0
(-5890 3635);
DISPLAY 0.680851 (-5890 3635);
PAINT MONO (-5890 3635);
FORCEPROP 0 LASTPIN (-5900 4075) $PN 29
J 0
(-5890 4085);
DISPLAY 0.680851 (-5890 4085);
PAINT MONO (-5890 4085);
FORCEPROP 0 LASTPIN (-5900 4525) $PN 28
J 0
(-5890 4535);
DISPLAY 0.680851 (-5890 4535);
PAINT MONO (-5890 4535);
FORCEPROP 0 LASTPIN (-5900 4975) $PN 27
J 0
(-5890 4985);
DISPLAY 0.680851 (-5890 4985);
PAINT MONO (-5890 4985);
FORCEPROP 0 LASTPIN (-5900 5425) $PN 26
J 0
(-5890 5435);
DISPLAY 0.680851 (-5890 5435);
PAINT MONO (-5890 5435);
FORCEPROP 0 LASTPIN (-5900 5875) $PN 25
J 0
(-5890 5885);
DISPLAY 0.680851 (-5890 5885);
PAINT MONO (-5890 5885);
FORCEPROP 0 LASTPIN (-5900 6325) $PN 24
J 0
(-5890 6335);
DISPLAY 0.680851 (-5890 6335);
PAINT MONO (-5890 6335);
FORCEPROP 0 LASTPIN (-5900 6775) $PN 23
J 0
(-5890 6785);
DISPLAY 0.680851 (-5890 6785);
PAINT MONO (-5890 6785);
FORCEPROP 0 LASTPIN (-7250 7725) $PN 13
J 2
(-7260 7735);
DISPLAY 0.680851 (-7260 7735);
PAINT MONO (-7260 7735);
FORCEPROP 0 LASTPIN (-7250 3475) $PN 20
J 2
(-7260 3485);
DISPLAY 0.680851 (-7260 3485);
PAINT MONO (-7260 3485);
FORCEPROP 0 LASTPIN (-7250 7875) $PN 12
J 2
(-7260 7885);
DISPLAY 0.680851 (-7260 7885);
PAINT MONO (-7260 7885);
FORCEPROP 0 LASTPIN (-7250 3075) $PN 16
J 2
(-7260 3085);
DISPLAY 0.680851 (-7260 3085);
PAINT MONO (-7260 3085);
FORCEPROP 0 LASTPIN (-7250 6725) $PN 10
J 2
(-7260 6735);
DISPLAY 0.680851 (-7260 6735);
PAINT MONO (-7260 6735);
FORCEPROP 0 LASTPIN (-7250 6575) $PN 9
J 2
(-7260 6585);
DISPLAY 0.680851 (-7260 6585);
PAINT MONO (-7260 6585);
FORCEPROP 0 LASTPIN (-5900 3725) $PN 1
J 0
(-5890 3735);
DISPLAY 0.680851 (-5890 3735);
PAINT MONO (-5890 3735);
FORCEPROP 0 LASTPIN (-5900 4175) $PN 2
J 0
(-5890 4185);
DISPLAY 0.680851 (-5890 4185);
PAINT MONO (-5890 4185);
FORCEPROP 0 LASTPIN (-5900 4625) $PN 3
J 0
(-5890 4635);
DISPLAY 0.680851 (-5890 4635);
PAINT MONO (-5890 4635);
FORCEPROP 0 LASTPIN (-5900 5075) $PN 4
J 0
(-5890 5085);
DISPLAY 0.680851 (-5890 5085);
PAINT MONO (-5890 5085);
FORCEPROP 0 LASTPIN (-5900 5525) $PN 5
J 0
(-5890 5535);
DISPLAY 0.680851 (-5890 5535);
PAINT MONO (-5890 5535);
FORCEPROP 0 LASTPIN (-5900 5975) $PN 6
J 0
(-5890 5985);
DISPLAY 0.680851 (-5890 5985);
PAINT MONO (-5890 5985);
FORCEPROP 0 LASTPIN (-5900 6425) $PN 7
J 0
(-5890 6435);
DISPLAY 0.680851 (-5890 6435);
PAINT MONO (-5890 6435);
FORCEPROP 0 LASTPIN (-5900 6875) $PN 8
J 0
(-5890 6885);
DISPLAY 0.680851 (-5890 6885);
PAINT MONO (-5890 6885);
FORCEPROP 0 LASTPIN (-7250 5575) $PN 22
J 2
(-7260 5585);
DISPLAY 0.680851 (-7260 5585);
PAINT MONO (-7260 5585);
FORCEPROP 0 LASTPIN (-7250 4475) $PN 31
J 2
(-7260 4485);
DISPLAY 0.680851 (-7260 4485);
PAINT MONO (-7260 4485);
FORCEPROP 0 LASTPIN (-7250 7425) $PN 17
J 2
(-7260 7435);
DISPLAY 0.680851 (-7260 7435);
PAINT MONO (-7260 7435);
FORCEPROP 0 LASTPIN (-7250 7275) $PN 18
J 2
(-7260 7285);
DISPLAY 0.680851 (-7260 7285);
PAINT MONO (-7260 7285);
FORCEPROP 0 LASTPIN (-5900 2675) $PN 35
J 0
(-5890 2685);
DISPLAY 0.680851 (-5890 2685);
PAINT MONO (-5890 2685);
FORCEPROP 0 LASTPIN (-5900 2975) $PN 36
J 0
(-5890 2985);
DISPLAY 0.680851 (-5890 2985);
PAINT MONO (-5890 2985);
FORCEPROP 0 LASTPIN (-7250 2325) $PN TH
J 2
(-7260 2335);
DISPLAY 0.680851 (-7260 2335);
PAINT MONO (-7260 2335);
FORCEPROP 0 LASTPIN (-5900 7875) $PN 39
J 0
(-5890 7885);
DISPLAY 0.680851 (-5890 7885);
PAINT MONO (-5890 7885);
FORCEPROP 0 LASTPIN (-5900 7575) $PN 40
J 0
(-5890 7585);
DISPLAY 0.680851 (-5890 7585);
PAINT MONO (-5890 7585);
FORCEPROP 0 LASTPIN (-7250 5825) $PN 21
J 2
(-7260 5835);
DISPLAY 0.680851 (-7260 5835);
PAINT MONO (-7260 5835);
FORCEPROP 0 LASTPIN (-7250 4725) $PN 32
J 2
(-7260 4735);
DISPLAY 0.680851 (-7260 4735);
PAINT MONO (-7260 4735);
FORCEPROP 2 LASTPIN (-7250 3625) $PN 15
J 2
(-7260 3635);
DISPLAY 0.680851 (-7260 3635);
PAINT MONO (-7260 3635);
FORCEPROP 2 LASTPIN (-7250 6425) $PN 11
J 2
(-7260 6435);
DISPLAY 0.680851 (-7260 6435);
PAINT MONO (-7260 6435);
FORCEPROP 2 LASTPIN (-7250 7125) $PN 19
J 2
(-7260 7135);
DISPLAY 0.680851 (-7260 7135);
PAINT MONO (-7260 7135);
FORCEPROP 2 LASTPIN (-5900 3375) $PN 14
J 0
(-5890 3385);
DISPLAY 0.680851 (-5890 3385);
PAINT MONO (-5890 3385);
FORCEPROP 2 LASTPIN (-7250 2425) $PN 38
J 2
(-7260 2435);
DISPLAY 0.680851 (-7260 2435);
PAINT MONO (-7260 2435);
FORCEPROP 2 LASTPIN (-7250 2525) $PN 37
J 2
(-7260 2535);
DISPLAY 0.680851 (-7260 2535);
PAINT MONO (-7260 2535);
FORCEPROP 1 LAST MATERIAL IC
J 0
(-7120 7983);
DISPLAY 0.617021 (-7120 7983);
PAINT GREEN (-7120 7983);
FORCEPROP 2 LAST PART_TYPE SMLF
J 0
(-6625 8125);
DISPLAY 0.638298 (-6625 8125);
FORCEPROP 2 LAST VALUE ISL69260IRAZ-T
J 0
(-6625 8075);
DISPLAY 0.617021 (-6625 8075);
FORCEPROP 1 LAST NEEDS_NO_SIZE TRUE
J 0
(-6575 5125);
DISPLAY 0.723404 (-6575 5125);
PAINT GREEN (-6575 5125);
DISPLAY INVISIBLE (-6575 5125);
FORCEPROP 2 LAST CDS_LIB pure_quanta
J 0
(-6575 5125);
DISPLAY INVISIBLE (-6575 5125);
FORCEPROP 1 LAST CDS_LMAN_SYM_OUTLINE -550,2850,500,-2850
J 0
(-6575 5125);
DISPLAY 0.468085 (-6575 5125);
PAINT GREEN (-6575 5125);
DISPLAY INVISIBLE (-6575 5125);
FORCEPROP 2 LAST SEC_TYPE 
J 0
(-7100 8225);
DISPLAY 0.680851 (-7100 8225);
DISPLAY INVISIBLE (-7100 8225);
FORCEPROP 1 LAST PATH I42
J 0
(-6575 5125);
DISPLAY 0.723404 (-6575 5125);
PAINT GREEN (-6575 5125);
DISPLAY INVISIBLE (-6575 5125);
FORCEPROP 1 LAST PART_NUMBER AL069260000
J 0
(-7120 8070);
DISPLAY 0.617021 (-7120 8070);
PAINT GREEN (-7120 8070);
DISPLAY INVISIBLE (-7120 8070);
FORCEADD UNIVERSAL_GND..1
(-7925 1800);
FORCEPROP 3 LASTPIN (-7925 1850) SIG_NAME GND\g
J 0
(-7915 1860);
DISPLAY 0.659574 (-7915 1860);
PAINT MONO (-7915 1860);
DISPLAY INVISIBLE (-7915 1860);
FORCEPROP 2 LAST CDS_LIB pure_quanta_power
J 0
(-7925 1800);
PAINT MONO (-7925 1800);
DISPLAY INVISIBLE (-7925 1800);
FORCEPROP 1 LAST HDL_POWER GND
J 1
(-7900 1725);
DISPLAY 0.872340 (-7900 1725);
PAINT GREEN (-7900 1725);
DISPLAY INVISIBLE (-7900 1725);
FORCEPROP 1 LAST PATH I5
J 0
(-7850 1800);
DISPLAY 0.872340 (-7850 1800);
PAINT AQUA (-7850 1800);
DISPLAY INVISIBLE (-7850 1800);
FORCEADD VCC15..1
(-9500 8150);
FORCEPROP 3 LASTPIN (-9500 8100) SIG_NAME P3V3_AUX\g
J 0
(-9490 8110);
DISPLAY 0.659574 (-9490 8110);
PAINT MONO (-9490 8110);
DISPLAY INVISIBLE (-9490 8110);
FORCEPROP 1 LAST HDL_POWER P3V3_AUX
J 1
(-9500 8200);
DISPLAY 0.617021 (-9500 8200);
PAINT GREEN (-9500 8200);
FORCEPROP 2 LAST CDS_LIB pure_quanta_power
J 0
(-9500 8150);
PAINT MONO (-9500 8150);
DISPLAY INVISIBLE (-9500 8150);
FORCEPROP 1 LAST PATH I51
J 0
(-9450 8175);
DISPLAY 0.872340 (-9450 8175);
PAINT AQUA (-9450 8175);
DISPLAY INVISIBLE (-9450 8175);
FORCEADD UNIVERSAL_GND..1
R 1
(-7750 8025);
FORCEPROP 3 LASTPIN (-7800 8025) SIG_NAME GND\g
J 0
(-7790 8035);
DISPLAY 0.659574 (-7790 8035);
PAINT MONO (-7790 8035);
DISPLAY INVISIBLE (-7790 8035);
FORCEPROP 2 LAST CDS_LIB pure_quanta_power
J 0
(-7750 8025);
PAINT MONO (-7750 8025);
DISPLAY INVISIBLE (-7750 8025);
FORCEPROP 1 LAST HDL_POWER GND
R 1
J 1
(-7675 8050);
DISPLAY 0.872340 (-7675 8050);
PAINT GREEN (-7675 8050);
DISPLAY INVISIBLE (-7675 8050);
FORCEPROP 1 LAST PATH I55
R 1
J 0
(-7750 8100);
DISPLAY 0.872340 (-7750 8100);
PAINT AQUA (-7750 8100);
DISPLAY INVISIBLE (-7750 8100);
FORCEADD UNIVERSAL_GND..1
(-5300 2250);
FORCEPROP 3 LASTPIN (-5300 2300) SIG_NAME GND\g
J 0
(-5290 2310);
DISPLAY 0.659574 (-5290 2310);
PAINT MONO (-5290 2310);
DISPLAY INVISIBLE (-5290 2310);
FORCEPROP 2 LAST CDS_LIB pure_quanta_power
J 0
(-5300 2250);
PAINT MONO (-5300 2250);
DISPLAY INVISIBLE (-5300 2250);
FORCEPROP 1 LAST HDL_POWER GND
J 1
(-5275 2175);
DISPLAY 0.872340 (-5275 2175);
PAINT GREEN (-5275 2175);
DISPLAY INVISIBLE (-5275 2175);
FORCEPROP 1 LAST PATH I56
J 0
(-5225 2250);
DISPLAY 0.872340 (-5225 2250);
PAINT AQUA (-5225 2250);
DISPLAY INVISIBLE (-5225 2250);
FORCEADD UNIVERSAL_GND..1
(-4600 2225);
FORCEPROP 3 LASTPIN (-4600 2275) SIG_NAME GND\g
J 0
(-4590 2285);
DISPLAY 0.659574 (-4590 2285);
PAINT MONO (-4590 2285);
DISPLAY INVISIBLE (-4590 2285);
FORCEPROP 2 LAST CDS_LIB pure_quanta_power
J 0
(-4600 2225);
DISPLAY INVISIBLE (-4600 2225);
FORCEPROP 1 LAST HDL_POWER GND
J 1
(-4575 2150);
DISPLAY 0.872340 (-4575 2150);
PAINT GREEN (-4575 2150);
DISPLAY INVISIBLE (-4575 2150);
FORCEPROP 1 LAST PATH I58
J 0
(-4525 2225);
DISPLAY 0.872340 (-4525 2225);
PAINT AQUA (-4525 2225);
DISPLAY INVISIBLE (-4525 2225);
FORCEADD OFFPAGE..4
(-3425 2675);
FORCEPROP 2 LAST $XR0 364 
J 0
(-3239 2675);
DISPLAY 0.638298 (-3239 2675);
PAINT MONO (-3239 2675);
FORCEPROP 2 LAST CDS_LIB standard
J 0
(-3425 2675);
DISPLAY INVISIBLE (-3425 2675);
FORCEPROP 1 LAST OFFPAGE TRUE
J 0
(-3100 2550);
DISPLAY 0.872340 (-3100 2550);
PAINT GREEN (-3100 2550);
DISPLAY INVISIBLE (-3100 2550);
FORCEPROP 1 LAST COMMENT_BODY TRUE
J 0
(-3450 2575);
DISPLAY 0.872340 (-3450 2575);
PAINT GREEN (-3450 2575);
DISPLAY INVISIBLE (-3450 2575);
FORCEPROP 2 LAST PATH I69
J 0
(-3225 2725);
DISPLAY 1.021277 (-3225 2725);
DISPLAY INVISIBLE (-3225 2725);
FORCEADD VCC15..1
(-3525 3825);
FORCEPROP 3 LASTPIN (-3525 3775) SIG_NAME P3V3_AUX\g
J 0
(-3515 3785);
DISPLAY 0.659574 (-3515 3785);
PAINT MONO (-3515 3785);
DISPLAY INVISIBLE (-3515 3785);
FORCEPROP 1 LAST HDL_POWER P3V3_AUX
J 1
(-3525 3875);
DISPLAY 0.617021 (-3525 3875);
PAINT GREEN (-3525 3875);
FORCEPROP 2 LAST CDS_LIB pure_quanta_power
J 0
(-3525 3825);
DISPLAY INVISIBLE (-3525 3825);
FORCEPROP 1 LAST PATH I74
J 0
(-3475 3850);
DISPLAY 0.872340 (-3475 3850);
PAINT AQUA (-3475 3850);
DISPLAY INVISIBLE (-3475 3850);
FORCEADD OFFPAGE..4
(-4975 6775);
FORCEPROP 2 LAST $XR0 364 
J 0
(-4789 6775);
DISPLAY 0.638298 (-4789 6775);
PAINT MONO (-4789 6775);
FORCEPROP 2 LAST CDS_LIB standard
J 0
(-4975 6775);
DISPLAY INVISIBLE (-4975 6775);
FORCEPROP 1 LAST OFFPAGE TRUE
J 0
(-4650 6650);
DISPLAY 0.872340 (-4650 6650);
PAINT GREEN (-4650 6650);
DISPLAY INVISIBLE (-4650 6650);
FORCEPROP 1 LAST COMMENT_BODY TRUE
J 0
(-5000 6675);
DISPLAY 0.872340 (-5000 6675);
PAINT GREEN (-5000 6675);
DISPLAY INVISIBLE (-5000 6675);
FORCEPROP 2 LAST PATH I86
J 0
(-4775 6825);
DISPLAY 1.021277 (-4775 6825);
DISPLAY INVISIBLE (-4775 6825);
FORCEADD OFFPAGE..2
(-4975 6875);
FORCEPROP 2 LAST $XR0 364 
J 0
(-4786 6875);
DISPLAY 0.638298 (-4786 6875);
PAINT MONO (-4786 6875);
FORCEPROP 2 LAST CDS_LIB standard
J 0
(-4975 6875);
DISPLAY INVISIBLE (-4975 6875);
FORCEPROP 1 LAST OFFPAGE TRUE
J 0
(-4650 6750);
DISPLAY 0.872340 (-4650 6750);
PAINT GREEN (-4650 6750);
DISPLAY INVISIBLE (-4650 6750);
FORCEPROP 1 LAST COMMENT_BODY TRUE
J 0
(-5020 6780);
DISPLAY 0.872340 (-5020 6780);
PAINT GREEN (-5020 6780);
DISPLAY INVISIBLE (-5020 6780);
FORCEPROP 2 LAST PATH I88
J 0
(-4775 6925);
DISPLAY 1.021277 (-4775 6925);
DISPLAY INVISIBLE (-4775 6925);
FORCEADD UNIVERSAL_GND..1
R 3
(-4825 7000);
FORCEPROP 3 LASTPIN (-4875 7000) SIG_NAME GND\g
J 0
(-4865 7010);
DISPLAY 0.659574 (-4865 7010);
PAINT MONO (-4865 7010);
DISPLAY INVISIBLE (-4865 7010);
FORCEPROP 2 LAST CDS_LIB pure_quanta_power
J 0
(-4825 7000);
PAINT MONO (-4825 7000);
DISPLAY INVISIBLE (-4825 7000);
FORCEPROP 1 LAST HDL_POWER GND
R 1
J 1
(-4750 6975);
DISPLAY 0.872340 (-4750 6975);
PAINT GREEN (-4750 6975);
DISPLAY INVISIBLE (-4750 6975);
FORCEPROP 1 LAST PATH I89
R 1
J 2
(-4825 6925);
DISPLAY 0.872340 (-4825 6925);
PAINT AQUA (-4825 6925);
DISPLAY INVISIBLE (-4825 6925);
FORCEADD OFFPAGE..2
(-4725 7400);
FORCEPROP 2 LAST $XR0 364 
J 0
(-4536 7400);
DISPLAY 0.638298 (-4536 7400);
PAINT MONO (-4536 7400);
FORCEPROP 2 LAST CDS_LIB standard
J 0
(-4725 7400);
DISPLAY INVISIBLE (-4725 7400);
FORCEPROP 1 LAST OFFPAGE TRUE
J 0
(-4400 7275);
DISPLAY 0.872340 (-4400 7275);
PAINT GREEN (-4400 7275);
DISPLAY INVISIBLE (-4400 7275);
FORCEPROP 1 LAST COMMENT_BODY TRUE
J 0
(-4770 7305);
DISPLAY 0.872340 (-4770 7305);
PAINT GREEN (-4770 7305);
DISPLAY INVISIBLE (-4770 7305);
FORCEPROP 2 LAST PATH I90
J 0
(-4400 7450);
DISPLAY 1.021277 (-4400 7450);
DISPLAY INVISIBLE (-4400 7450);
FORCEADD UNIVERSAL_GND..1
R 3
(-4825 7475);
FORCEPROP 3 LASTPIN (-4875 7475) SIG_NAME GND\g
J 0
(-4865 7485);
DISPLAY 0.659574 (-4865 7485);
PAINT MONO (-4865 7485);
DISPLAY INVISIBLE (-4865 7485);
FORCEPROP 2 LAST CDS_LIB pure_quanta_power
J 0
(-4825 7475);
PAINT MONO (-4825 7475);
DISPLAY INVISIBLE (-4825 7475);
FORCEPROP 1 LAST HDL_POWER GND
R 1
J 1
(-4750 7450);
DISPLAY 0.872340 (-4750 7450);
PAINT GREEN (-4750 7450);
DISPLAY INVISIBLE (-4750 7450);
FORCEPROP 1 LAST PATH I91
R 1
J 2
(-4825 7400);
DISPLAY 0.872340 (-4825 7400);
PAINT AQUA (-4825 7400);
DISPLAY INVISIBLE (-4825 7400);
FORCEADD VCC15..1
(-4475 8000);
FORCEPROP 3 LASTPIN (-4475 7950) SIG_NAME P3V3_AUX\g
J 0
(-4465 7960);
DISPLAY 0.659574 (-4465 7960);
PAINT MONO (-4465 7960);
DISPLAY INVISIBLE (-4465 7960);
FORCEPROP 1 LAST HDL_POWER P3V3_AUX
J 1
(-4475 8050);
DISPLAY 0.617021 (-4475 8050);
PAINT GREEN (-4475 8050);
FORCEPROP 2 LAST CDS_LIB pure_quanta_power
J 0
(-4475 8000);
DISPLAY INVISIBLE (-4475 8000);
FORCEPROP 1 LAST PATH I93
J 0
(-4425 8025);
DISPLAY 0.872340 (-4425 8025);
PAINT AQUA (-4425 8025);
DISPLAY INVISIBLE (-4425 8025);
FORCEADD Q_RES..1
(-9300 6725);
FORCEPROP 1 LAST LOCATION R646
J 0
(-9525 6725);
DISPLAY 0.638298 (-9525 6725);
FORCEPROP 2 LAST SEC 1
J 0
(-9350 6925);
DISPLAY 0.680851 (-9350 6925);
PAINT MONO (-9350 6925);
DISPLAY INVISIBLE (-9350 6925);
FORCEPROP 1 LASTPIN (-9400 6725) $PN 1
J 0
(-9388 6737);
DISPLAY 0.787234 (-9388 6737);
PAINT MONO (-9388 6737);
FORCEPROP 1 LASTPIN (-9200 6725) $PN 2
J 0
(-9238 6737);
DISPLAY 0.787234 (-9238 6737);
PAINT MONO (-9238 6737);
FORCEPROP 1 LAST MATERIAL CHIP
J 0
(-9175 6525);
DISPLAY 0.510638 (-9175 6525);
FORCEPROP 1 LAST PACK_TYPE 0402LF
J 0
(-8900 6525);
DISPLAY 0.510638 (-8900 6525);
FORCEPROP 1 LAST TOLERANCE 5%
J 0
(-9025 6725);
DISPLAY 0.510638 (-9025 6725);
FORCEPROP 1 LAST VALUE 0
J 2
(-9075 6725);
DISPLAY 0.510638 (-9075 6725);
FORCEPROP 1 LAST WATTAGE 1/16W
J 2
(-8925 6525);
DISPLAY 0.510638 (-8925 6525);
FORCEPROP 2 LAST SEC_TYPE 0402LF
J 0
(-9350 6925);
DISPLAY 1.021277 (-9350 6925);
DISPLAY INVISIBLE (-9350 6925);
FORCEPROP 2 LAST CDS_LIB pure_quanta
J 0
(-9300 6725);
DISPLAY INVISIBLE (-9300 6725);
FORCEPROP 1 LAST PATH I94
J 0
(-9350 6875);
DISPLAY 0.978723 (-9350 6875);
PAINT WHITE (-9350 6875);
DISPLAY INVISIBLE (-9350 6875);
FORCEPROP 1 LAST PART_NUMBER CS00002JB13
J 0
(-9175 6475);
DISPLAY 0.510638 (-9175 6475);
DISPLAY INVISIBLE (-9175 6475);
FORCEADD Q_RES..1
(-9300 6575);
FORCEPROP 1 LAST LOCATION R647
J 0
(-9525 6575);
DISPLAY 0.638298 (-9525 6575);
FORCEPROP 2 LAST SEC 1
J 0
(-9350 6775);
DISPLAY 0.680851 (-9350 6775);
PAINT MONO (-9350 6775);
DISPLAY INVISIBLE (-9350 6775);
FORCEPROP 1 LASTPIN (-9400 6575) $PN 1
J 0
(-9388 6587);
DISPLAY 0.787234 (-9388 6587);
PAINT MONO (-9388 6587);
FORCEPROP 1 LASTPIN (-9200 6575) $PN 2
J 0
(-9238 6587);
DISPLAY 0.787234 (-9238 6587);
PAINT MONO (-9238 6587);
FORCEPROP 1 LAST TOLERANCE 5%
J 0
(-9025 6575);
DISPLAY 0.510638 (-9025 6575);
FORCEPROP 1 LAST VALUE 0
J 2
(-9075 6575);
DISPLAY 0.510638 (-9075 6575);
FORCEPROP 2 LAST CDS_LIB pure_quanta
J 0
(-9300 6575);
DISPLAY INVISIBLE (-9300 6575);
FORCEPROP 2 LAST SEC_TYPE 0402LF
J 0
(-9350 6775);
DISPLAY 1.021277 (-9350 6775);
DISPLAY INVISIBLE (-9350 6775);
FORCEPROP 1 LAST MATERIAL CHIP
J 0
(-9425 6700);
DISPLAY 0.510638 (-9425 6700);
DISPLAY INVISIBLE (-9425 6700);
FORCEPROP 1 LAST WATTAGE 1/16W
J 2
(-9175 6700);
DISPLAY 0.510638 (-9175 6700);
DISPLAY INVISIBLE (-9175 6700);
FORCEPROP 1 LAST PACK_TYPE 0402LF
J 0
(-9150 6700);
DISPLAY 0.510638 (-9150 6700);
DISPLAY INVISIBLE (-9150 6700);
FORCEPROP 1 LAST PATH I95
J 0
(-9350 6725);
DISPLAY 0.978723 (-9350 6725);
PAINT WHITE (-9350 6725);
DISPLAY INVISIBLE (-9350 6725);
FORCEPROP 1 LAST PART_NUMBER CS00002JB13
J 0
(-9425 6650);
DISPLAY 0.510638 (-9425 6650);
DISPLAY INVISIBLE (-9425 6650);
FORCEADD DNS..2
(-9350 7125);
PAINT RED (-9350 7125);
FORCEPROP 2 LAST CDS_LIB mstr_misc
J 0
(-9350 7125);
DISPLAY INVISIBLE (-9350 7125);
FORCEPROP 1 LAST COMMENT_BODY TRUE
R 1
J 0
(-9275 6900);
DISPLAY 0.872340 (-9275 6900);
PAINT GREEN (-9275 6900);
DISPLAY INVISIBLE (-9275 6900);
FORCEADD DNS..2
(-9350 7300);
PAINT RED (-9350 7300);
FORCEPROP 2 LAST CDS_LIB mstr_misc
J 0
(-9350 7300);
DISPLAY INVISIBLE (-9350 7300);
FORCEPROP 1 LAST COMMENT_BODY TRUE
R 1
J 0
(-9275 7075);
DISPLAY 0.872340 (-9275 7075);
PAINT GREEN (-9275 7075);
DISPLAY INVISIBLE (-9275 7075);
FORCEADD DNS..2
(-8275 6950);
PAINT RED (-8275 6950);
FORCEPROP 2 LAST CDS_LIB mstr_misc
J 0
(-8275 6950);
DISPLAY INVISIBLE (-8275 6950);
FORCEPROP 1 LAST COMMENT_BODY TRUE
R 1
J 0
(-8200 6725);
DISPLAY 0.872340 (-8200 6725);
PAINT GREEN (-8200 6725);
DISPLAY INVISIBLE (-8200 6725);
FORCEADD DNS..2
(-9075 2550);
PAINT RED (-9075 2550);
FORCEPROP 2 LAST CDS_LIB mstr_misc
J 0
(-9075 2550);
DISPLAY INVISIBLE (-9075 2550);
FORCEPROP 1 LAST COMMENT_BODY TRUE
R 1
J 0
(-9000 2325);
DISPLAY 0.872340 (-9000 2325);
PAINT GREEN (-9000 2325);
DISPLAY INVISIBLE (-9000 2325);
FORCEADD DNS..2
(-8050 2075);
PAINT RED (-8050 2075);
FORCEPROP 2 LAST CDS_LIB mstr_misc
J 0
(-8050 2075);
DISPLAY INVISIBLE (-8050 2075);
FORCEPROP 1 LAST COMMENT_BODY TRUE
R 1
J 0
(-7975 1850);
DISPLAY 0.872340 (-7975 1850);
PAINT GREEN (-7975 1850);
DISPLAY INVISIBLE (-7975 1850);
FORCEADD DNS..2
(-8650 2100);
PAINT RED (-8650 2100);
FORCEPROP 2 LAST CDS_LIB mstr_misc
J 0
(-8650 2100);
DISPLAY INVISIBLE (-8650 2100);
FORCEPROP 1 LAST COMMENT_BODY TRUE
R 1
J 0
(-8575 1875);
DISPLAY 0.872340 (-8575 1875);
PAINT GREEN (-8575 1875);
DISPLAY INVISIBLE (-8575 1875);
FORCEADD DNS..2
(-4600 2450);
PAINT RED (-4600 2450);
FORCEPROP 2 LAST CDS_LIB mstr_misc
J 0
(-4600 2450);
DISPLAY INVISIBLE (-4600 2450);
FORCEPROP 1 LAST COMMENT_BODY TRUE
R 1
J 0
(-4525 2225);
DISPLAY 0.872340 (-4525 2225);
PAINT GREEN (-4525 2225);
DISPLAY INVISIBLE (-4525 2225);
FORCEADD DNS..2
(-9150 8075);
PAINT RED (-9150 8075);
FORCEPROP 2 LAST CDS_LIB mstr_misc
J 0
(-9150 8075);
DISPLAY INVISIBLE (-9150 8075);
FORCEPROP 1 LAST COMMENT_BODY TRUE
R 1
J 0
(-9075 7850);
DISPLAY 0.872340 (-9075 7850);
PAINT GREEN (-9075 7850);
DISPLAY INVISIBLE (-9075 7850);
FORCEADD DNS..2
(-9275 6450);
PAINT RED (-9275 6450);
FORCEPROP 2 LAST CDS_LIB mstr_misc
J 0
(-9275 6450);
DISPLAY INVISIBLE (-9275 6450);
FORCEPROP 1 LAST COMMENT_BODY TRUE
R 1
J 0
(-9200 6225);
DISPLAY 0.872340 (-9200 6225);
PAINT GREEN (-9200 6225);
DISPLAY INVISIBLE (-9200 6225);
FORCEADD DNS..2
(-9350 7450);
PAINT RED (-9350 7450);
FORCEPROP 2 LAST CDS_LIB mstr_misc
J 0
(-9350 7450);
DISPLAY INVISIBLE (-9350 7450);
FORCEPROP 1 LAST COMMENT_BODY TRUE
R 1
J 0
(-9275 7225);
DISPLAY 0.872340 (-9275 7225);
PAINT GREEN (-9275 7225);
DISPLAY INVISIBLE (-9275 7225);
FORCEADD QUANTA_TITLE_BLOCK_C..1
(-2400 1600);
FORCEPROP 0 LAST CDS_CON_LAST_MODIFIED Thu Sep 14 16:13:02 2023
J 0
(-4285 1615);
DISPLAY INVISIBLE (-4285 1615);
FORCEPROP 1 LAST CUSTOM_TXT_CDS <CON_LAST_MODIFIED>
J 0
(-4285 1615);
DISPLAY 0.978723 (-4285 1615);
FORCEPROP 2 LAST CUSTOM_TXT_CDS <XR_PAGE_TITLE>
J 0
(-10290 6850);
DISPLAY 0.638298 (-10290 6850);
PAINT PINK (-10290 6850);
DISPLAY INVISIBLE (-10290 6850);
FORCEPROP 1 LAST CUSTOM_TXT_CDS <NAME_2>
J 0
(-5575 1650);
FORCEPROP 1 LAST CUSTOM_TXT_CDS <NAME_1>
J 0
(-5575 1775);
FORCEPROP 1 LAST CUSTOM_TXT_CDS <Q_NUMBER>
J 0
(-3803 1703);
DISPLAY 1.212766 (-3803 1703);
FORCEPROP 1 LAST CUSTOM_TXT_CDS <Q_PROJ>
J 0
(-4782 1702);
DISPLAY 1.212766 (-4782 1702);
FORCEPROP 1 LAST CUSTOM_TXT_CDS <Q_REV>
J 0
(-2584 1703);
DISPLAY 1.212766 (-2584 1703);
FORCEPROP 1 LAST CUSTOM_TXT_CDS <CON_PAGE_NUM> OF <CON_TOTAL_PAGES>
J 0
(-2846 1618);
DISPLAY 0.978723 (-2846 1618);
FORCEPROP 1 LAST Q_TITLE P0V9_CPU0_RT_2D_VR_CONTROLLER
J 0
(-11700 1650);
DISPLAY 2.446809 (-11700 1650);
PAINT GREEN (-11700 1650);
FORCEPROP 2 LAST PAGE_BORDER TRUE
J 0
(-10290 6850);
DISPLAY 0.638298 (-10290 6850);
PAINT PINK (-10290 6850);
DISPLAY INVISIBLE (-10290 6850);
FORCEPROP 1 LAST CDS_LMAN_SYM_OUTLINE -9475,6775,100,-125
J 0
(-2400 1600);
DISPLAY 0.468085 (-2400 1600);
PAINT GREEN (-2400 1600);
DISPLAY INVISIBLE (-2400 1600);
FORCEPROP 2 LAST CDS_LIB pure_quanta
J 0
(-2400 1600);
DISPLAY INVISIBLE (-2400 1600);
FORCEPROP 2 LAST CDS_XR_PAGE_TITLE CR-363 : @T6G_MB_LIB.T6G(SCH_1):PAGE363
J 0
(-10290 6850);
DISPLAY 0.638298 (-10290 6850);
PAINT PINK (-10290 6850);
DISPLAY INVISIBLE (-10290 6850);
FORCEPROP 1 LAST Q_DEPT BU9
J 1
(-6163 1649);
DISPLAY 1.957447 (-6163 1649);
PAINT GREEN (-6163 1649);
DISPLAY INVISIBLE (-6163 1649);
FORCEPROP 1 LAST COMMENT_BODY TRUE
J 0
(-2388 1587);
DISPLAY 0.978723 (-2388 1587);
PAINT GREEN (-2388 1587);
DISPLAY INVISIBLE (-2388 1587);
FORCEADD DNS..2
(-9500 2275);
PAINT RED (-9500 2275);
FORCEPROP 2 LAST CDS_LIB mstr_misc
J 0
(-9500 2275);
DISPLAY INVISIBLE (-9500 2275);
FORCEPROP 1 LAST COMMENT_BODY TRUE
R 1
J 0
(-9425 2050);
DISPLAY 0.872340 (-9425 2050);
PAINT GREEN (-9425 2050);
DISPLAY INVISIBLE (-9425 2050);
FORCEADD DNS..2
(-8450 8050);
PAINT RED (-8450 8050);
FORCEPROP 2 LAST CDS_LIB mstr_misc
J 0
(-8450 8050);
DISPLAY INVISIBLE (-8450 8050);
FORCEPROP 1 LAST COMMENT_BODY TRUE
R 1
J 0
(-8375 7825);
DISPLAY 0.872340 (-8375 7825);
PAINT GREEN (-8375 7825);
DISPLAY INVISIBLE (-8375 7825);
WIRE 16 -1 (-8900 2775)(-8650 2775);
WIRE 16 -1 (-8900 2775)(-8900 2725);
WIRE 16 -1 (-10275 3400)(-10625 3400);
WIRE 16 -1 (-4700 5875)(-4475 5875);
WIRE 16 -1 (-4475 5875)(-4475 5775);
WIRE 16 -1 (-4700 5425)(-4450 5425);
WIRE 16 -1 (-4450 5425)(-4450 5275);
WIRE 16 -1 (-4675 4975)(-4450 4975);
WIRE 16 -1 (-4450 4975)(-4450 4800);
WIRE 16 -1 (-4675 4525)(-4425 4525);
WIRE 16 -1 (-4425 4525)(-4425 4325);
WIRE 16 -1 (-4675 4075)(-4450 4075);
WIRE 16 -1 (-4450 4075)(-4450 3900);
WIRE 16 -1 (-4725 3625)(-4375 3625);
WIRE 16 -1 (-4375 3625)(-4375 3500);
WIRE 16 -1 (-10675 5500)(-10850 5500);
WIRE 16 -1 (-10850 5500)(-10850 5300);
WIRE 16 -1 (-7250 4725)(-7800 4725);
WIRE 16 -1 (-7800 4725)(-7800 4625);
WIRE 16 -1 (-4725 2975)(-4550 2975);
WIRE 16 -1 (-4550 2975)(-4550 2900);
WIRE 16 -1 (-10475 7350)(-10475 7200);
WIRE 16 -1 (-10325 8050)(-10050 8050);
WIRE 16 -1 (-10325 8050)(-10325 8100);
WIRE 16 -1 (-9450 5350)(-9450 5300);
WIRE 16 -1 (-9450 5350)(-9875 5350);
WIRE 16 -1 (-9500 8025)(-9250 8025);
WIRE 16 -1 (-9500 8025)(-9500 8100);
WIRE 16 -1 (-8350 8025)(-7800 8025);
WIRE 16 -1 (-5300 2300)(-5300 2375);
WIRE 16 -1 (-4600 2275)(-4600 2375);
WIRE 16 -1 (-3525 3775)(-3525 3725);
WIRE 16 -1 (-5900 6775)(-5025 6775);
FORCEPROP 2 LAST SIG_NAME P0V9_RETIMER_CPU0_IMON1
J 0
(-5735 6785);
DISPLAY 0.617021 (-5735 6785);
WIRE 16 -1 (-10250 5350)(-10075 5350);
WIRE 16 -1 (-10250 5350)(-10250 5500);
WIRE 16 -1 (-10250 5500)(-8450 5500);
FORCEPROP 2 LAST SIG_NAME P0V9_RETIMER_CPU0_SENSE_SH_N
J 0
(-10085 5510);
DISPLAY 0.617021 (-10085 5510);
FORCEPROP 2 LASTPROP $XRERR UNIQUE?
J 0
(-10325 5510);
DISPLAY 0.638298 (-10325 5510);
PAINT MONO (-10325 5510);
DISPLAY INVISIBLE (-10325 5510);
WIRE 16 -1 (-10250 5500)(-10425 5500);
WIRE 16 -1 (-7800 5500)(-8450 5500);
WIRE 16 -1 (-8450 5600)(-8450 5500);
WIRE 16 -1 (-7800 5500)(-7800 5575);
WIRE 16 -1 (-7250 5575)(-7800 5575);
WIRE 2 2175 (-2500 8100)(-2500 7300);
WIRE 2 2175 (-4100 8100)(-2500 8100);
WIRE 2 2175 (-2500 7300)(-4100 7300);
WIRE 2 2175 (-4100 7300)(-4100 8100);
WIRE 16 -1 (-5900 6325)(-5025 6325);
FORCEPROP 2 LAST SIG_NAME P0V9_RETIMER_CPU0_IMON2
J 0
(-5710 6335);
DISPLAY 0.617021 (-5710 6335);
WIRE 16 -1 (-7800 5825)(-7250 5825);
WIRE 16 -1 (-7800 5875)(-7800 5825);
WIRE 16 -1 (-7800 5875)(-8450 5875);
FORCEPROP 2 LAST SIG_NAME P0V9_RETIMER_CPU0_SENSE_R_P
J 0
(-8560 5885);
DISPLAY 0.617021 (-8560 5885);
FORCEPROP 2 LASTPROP $XRERR UNIQUE?
J 0
(-8800 5885);
DISPLAY 0.638298 (-8800 5885);
PAINT MONO (-8800 5885);
DISPLAY INVISIBLE (-8800 5885);
WIRE 16 -1 (-8450 5800)(-8450 5875);
WIRE 16 -1 (-8800 5875)(-8450 5875);
WIRE 16 -1 (-3525 3525)(-3525 3375);
WIRE 16 -1 (-4675 3375)(-3525 3375);
FORCEPROP 2 LAST SIG_NAME TP_P0V9_RETIMER_CPU0_VRHOT
J 0
(-4360 3385);
DISPLAY 0.638298 (-4360 3385);
FORCEPROP 2 LASTPROP $XRERR UNIQUE?
J 0
(-4600 3385);
DISPLAY 0.638298 (-4600 3385);
PAINT MONO (-4600 3385);
DISPLAY INVISIBLE (-4600 3385);
WIRE 16 -1 (-11025 6575)(-9400 6575);
FORCEPROP 2 LAST SIG_NAME P0V9_RETIMER_CPU0_PMSDA
J 0
(-10935 6585);
DISPLAY 0.680851 (-10935 6585);
WIRE 16 -1 (-11050 6725)(-9400 6725);
FORCEPROP 2 LAST SIG_NAME P0V9_RETIMER_CPU0_PMSCL
J 0
(-10935 6735);
DISPLAY 0.680851 (-10935 6735);
WIRE 16 -1 (-10600 7725)(-9400 7725);
FORCEPROP 2 LAST SIG_NAME P0V9_RETIMER_CPU0_EN
J 0
(-10510 7735);
DISPLAY 0.808511 (-10510 7735);
WIRE 16 -1 (-11350 7875)(-10050 7875);
FORCEPROP 2 LAST SIG_NAME PWRGD_P0V9_RETIMER_CPU0
J 0
(-11260 7885);
DISPLAY 0.765957 (-11260 7885);
WIRE 16 -1 (-10250 6025)(-10025 6025);
WIRE 16 -1 (-10250 6025)(-10250 5875);
WIRE 16 -1 (-10250 5875)(-9000 5875);
WIRE 16 -1 (-10425 5875)(-10250 5875);
FORCEPROP 2 LAST SIG_NAME P0V9_RETIMER_CPU0_SENSE_SH_P
J 0
(-10085 5885);
DISPLAY 0.617021 (-10085 5885);
FORCEPROP 2 LASTPROP $XRERR UNIQUE?
J 0
(-10325 5885);
DISPLAY 0.638298 (-10325 5885);
PAINT MONO (-10325 5885);
DISPLAY INVISIBLE (-10325 5885);
WIRE 16 -1 (-5900 3625)(-4925 3625);
FORCEPROP 2 LAST SIG_NAME NC_P0V9_RETIMER_CPU0_IMON8
J 0
(-5785 3635);
DISPLAY 0.617021 (-5785 3635);
FORCEPROP 2 LASTPROP $XRERR UNIQUE?
J 0
(-6025 3635);
DISPLAY 0.638298 (-6025 3635);
PAINT MONO (-6025 3635);
DISPLAY INVISIBLE (-6025 3635);
WIRE 16 -1 (-4600 2575)(-4600 2675);
WIRE 16 -1 (-3475 2675)(-4600 2675);
WIRE 16 -1 (-4600 2675)(-5300 2675);
WIRE 16 -1 (-5300 2575)(-5300 2675);
WIRE 16 -1 (-5900 2675)(-5300 2675);
FORCEPROP 2 LAST SIG_NAME P0V9_RETIMER_CPU0_TEMP0
J 0
(-5785 2685);
DISPLAY 0.638298 (-5785 2685);
WIRE 16 -1 (-8725 3975)(-8725 3875);
WIRE 16 -1 (-7250 3875)(-8725 3875);
FORCEPROP 2 LAST SIG_NAME P0V9_RETIMER_CPU0_CFP
J 0
(-8110 3885);
DISPLAY 0.638298 (-8110 3885);
FORCEPROP 2 LASTPROP $XRERR UNIQUE?
J 0
(-8350 3885);
DISPLAY 0.638298 (-8350 3885);
PAINT MONO (-8350 3885);
DISPLAY INVISIBLE (-8350 3885);
WIRE 16 -1 (-5900 4525)(-4875 4525);
FORCEPROP 2 LAST SIG_NAME NC_P0V9_RETIMER_CPU0_IMON6
J 0
(-5785 4535);
DISPLAY 0.617021 (-5785 4535);
FORCEPROP 2 LASTPROP $XRERR UNIQUE?
J 0
(-6025 4535);
DISPLAY 0.638298 (-6025 4535);
PAINT MONO (-6025 4535);
DISPLAY INVISIBLE (-6025 4535);
WIRE 16 -1 (-5900 4625)(-5025 4625);
FORCEPROP 2 LAST SIG_NAME NC_P0V9_RETIMER_CPU0_PWM6
J 0
(-5785 4635);
DISPLAY 0.617021 (-5785 4635);
FORCEPROP 2 LASTPROP $XRERR UNIQUE?
J 0
(-5020 4625);
DISPLAY 0.638298 (-5020 4625);
PAINT MONO (-5020 4625);
DISPLAY INVISIBLE (-5020 4625);
WIRE 16 -1 (-5900 4075)(-4875 4075);
FORCEPROP 2 LAST SIG_NAME NC_P0V9_RETIMER_CPU0_IMON7
J 0
(-5785 4085);
DISPLAY 0.617021 (-5785 4085);
FORCEPROP 2 LASTPROP $XRERR UNIQUE?
J 0
(-6025 4085);
DISPLAY 0.638298 (-6025 4085);
PAINT MONO (-6025 4085);
DISPLAY INVISIBLE (-6025 4085);
WIRE 16 -1 (-9100 3975)(-9100 3625);
WIRE 16 -1 (-7250 3625)(-9100 3625);
FORCEPROP 2 LAST SIG_NAME P0V9_RETIMER_CPU0_INALERT
J 0
(-8235 3635);
DISPLAY 0.638298 (-8235 3635);
FORCEPROP 2 LASTPROP $XRERR UNIQUE?
J 0
(-8475 3635);
DISPLAY 0.638298 (-8475 3635);
PAINT MONO (-8475 3635);
DISPLAY INVISIBLE (-8475 3635);
WIRE 16 -1 (-5900 2975)(-4925 2975);
FORCEPROP 2 LAST SIG_NAME P0V9_RETIMER_CPU0_TEMP1_R
J 0
(-5785 2985);
DISPLAY 0.638298 (-5785 2985);
FORCEPROP 2 LASTPROP $XRERR UNIQUE?
J 0
(-6025 2985);
DISPLAY 0.638298 (-6025 2985);
PAINT MONO (-6025 2985);
DISPLAY INVISIBLE (-6025 2985);
WIRE 16 -1 (-5900 4175)(-5025 4175);
FORCEPROP 2 LAST SIG_NAME NC_P0V9_RETIMER_CPU0_PWM7
J 0
(-5785 4185);
DISPLAY 0.617021 (-5785 4185);
FORCEPROP 2 LASTPROP $XRERR UNIQUE?
J 0
(-5020 4175);
DISPLAY 0.638298 (-5020 4175);
PAINT MONO (-5020 4175);
DISPLAY INVISIBLE (-5020 4175);
WIRE 16 -1 (-5900 5975)(-5025 5975);
FORCEPROP 2 LAST SIG_NAME NC_P0V9_RETIMER_CPU0_PWM3
J 0
(-5710 5985);
DISPLAY 0.617021 (-5710 5985);
FORCEPROP 2 LASTPROP $XRERR UNIQUE?
J 0
(-5020 5975);
DISPLAY 0.638298 (-5020 5975);
PAINT MONO (-5020 5975);
DISPLAY INVISIBLE (-5020 5975);
WIRE 16 -1 (-5900 5525)(-5025 5525);
FORCEPROP 2 LAST SIG_NAME NC_P0V9_RETIMER_CPU0_PWM4
J 0
(-5710 5535);
DISPLAY 0.617021 (-5710 5535);
FORCEPROP 2 LASTPROP $XRERR UNIQUE?
J 0
(-5020 5525);
DISPLAY 0.638298 (-5020 5525);
PAINT MONO (-5020 5525);
DISPLAY INVISIBLE (-5020 5525);
WIRE 16 -1 (-7250 6575)(-9200 6575);
FORCEPROP 2 LAST SIG_NAME P0V9_RETIMER_CPU0_PMSDA_R
J 0
(-8235 6585);
DISPLAY 0.617021 (-8235 6585);
FORCEPROP 2 LASTPROP $XRERR UNIQUE?
J 0
(-8475 6585);
DISPLAY 0.638298 (-8475 6585);
PAINT MONO (-8475 6585);
DISPLAY INVISIBLE (-8475 6585);
WIRE 16 -1 (-8875 7725)(-8875 7675);
WIRE 16 -1 (-8875 7725)(-7250 7725);
FORCEPROP 2 LAST SIG_NAME P0V9_RETIMER_CPU0_EN0_R
J 0
(-8385 7735);
DISPLAY 0.808511 (-8385 7735);
FORCEPROP 2 LASTPROP $XRERR UNIQUE?
J 0
(-8625 7735);
DISPLAY 0.638298 (-8625 7735);
PAINT MONO (-8625 7735);
DISPLAY INVISIBLE (-8625 7735);
WIRE 16 -1 (-9200 7725)(-8875 7725);
WIRE 16 -1 (-8875 7675)(-10475 7675);
WIRE 16 -1 (-10475 7675)(-10475 7550);
WIRE 16 -1 (-7250 6425)(-9200 6425);
FORCEPROP 2 LAST SIG_NAME TP_P0V9_RETIMER_CPU0_PMALERT
J 0
(-8310 6435);
DISPLAY 0.617021 (-8310 6435);
FORCEPROP 2 LASTPROP $XRERR UNIQUE?
J 0
(-8550 6435);
DISPLAY 0.638298 (-8550 6435);
PAINT MONO (-8550 6435);
DISPLAY INVISIBLE (-8550 6435);
WIRE 16 -1 (-7250 3075)(-8500 3075);
FORCEPROP 2 LAST SIG_NAME NC_P0V9_RETIMER_CPU0_PG1
J 0
(-8185 3085);
DISPLAY 0.617021 (-8185 3085);
FORCEPROP 2 LASTPROP $XRERR UNIQUE?
J 0
(-8740 3075);
DISPLAY 0.638298 (-8740 3075);
PAINT MONO (-8740 3075);
DISPLAY INVISIBLE (-8740 3075);
WIRE 16 -1 (-5900 5875)(-4900 5875);
FORCEPROP 2 LAST SIG_NAME NC_P0V9_RETIMER_CPU0_IMON3
J 0
(-5710 5885);
DISPLAY 0.617021 (-5710 5885);
FORCEPROP 2 LASTPROP $XRERR UNIQUE?
J 0
(-5950 5885);
DISPLAY 0.638298 (-5950 5885);
PAINT MONO (-5950 5885);
DISPLAY INVISIBLE (-5950 5885);
WIRE 16 -1 (-4875 3375)(-5900 3375);
FORCEPROP 2 LAST SIG_NAME P0V9_RETIMER_CPU0_VRHOT
J 0
(-5785 3385);
DISPLAY 0.638298 (-5785 3385);
FORCEPROP 2 LASTPROP $XRERR UNIQUE?
J 0
(-6025 3385);
DISPLAY 0.638298 (-6025 3385);
PAINT MONO (-6025 3385);
DISPLAY INVISIBLE (-6025 3385);
WIRE 16 -1 (-9275 7275)(-8650 7275);
WIRE 16 -1 (-8650 7275)(-7250 7275);
WIRE 16 -1 (-8650 7050)(-8650 7275);
FORCEPROP 2 LAST SIG_NAME P0V9_RETIMER_CPU0_SVID_SDA
J 0
(-8485 7285);
DISPLAY 0.808511 (-8485 7285);
FORCEPROP 2 LASTPROP $XRERR UNIQUE?
J 0
(-8725 7285);
DISPLAY 0.638298 (-8725 7285);
PAINT MONO (-8725 7285);
DISPLAY INVISIBLE (-8725 7285);
WIRE 16 -1 (-7250 6725)(-9200 6725);
FORCEPROP 2 LAST SIG_NAME P0V9_RETIMER_CPU0_PMSCL_R
J 0
(-8235 6735);
DISPLAY 0.617021 (-8235 6735);
FORCEPROP 2 LASTPROP $XRERR UNIQUE?
J 0
(-8475 6735);
DISPLAY 0.638298 (-8475 6735);
PAINT MONO (-8475 6735);
DISPLAY INVISIBLE (-8475 6735);
WIRE 16 -1 (-9500 3475)(-7250 3475);
FORCEPROP 2 LAST SIG_NAME P0V9_RETIMER_CPU0_EN1_R
J 0
(-8360 3485);
DISPLAY 0.808511 (-8360 3485);
FORCEPROP 2 LASTPROP $XRERR UNIQUE?
J 0
(-8600 3485);
DISPLAY 0.638298 (-8600 3485);
PAINT MONO (-8600 3485);
DISPLAY INVISIBLE (-8600 3485);
WIRE 16 -1 (-9500 3475)(-9500 3400);
WIRE 16 -1 (-9500 3400)(-10075 3400);
WIRE 16 -1 (-9850 8050)(-9575 8050);
WIRE 16 -1 (-9575 8050)(-9575 7875);
WIRE 16 -1 (-8775 7875)(-9575 7875);
WIRE 16 -1 (-9850 7875)(-9575 7875);
WIRE 16 -1 (-8775 7875)(-7250 7875);
FORCEPROP 2 LAST SIG_NAME PWRGD_P0V9_RETIMER_CPU0_R
J 0
(-8410 7885);
DISPLAY 0.765957 (-8410 7885);
FORCEPROP 2 LASTPROP $XRERR UNIQUE?
J 0
(-8650 7885);
DISPLAY 0.638298 (-8650 7885);
PAINT MONO (-8650 7885);
DISPLAY INVISIBLE (-8650 7885);
WIRE 16 -1 (-8775 7875)(-8775 8025);
WIRE 16 -1 (-8550 8025)(-8775 8025);
WIRE 16 -1 (-8775 8025)(-9050 8025);
WIRE 16 -1 (-5675 7100)(-5675 7000);
WIRE 16 -1 (-5675 7000)(-5275 7000);
WIRE 16 -1 (-4875 7000)(-5275 7000);
WIRE 16 -1 (-5275 7000)(-5275 7100);
WIRE 16 -1 (-8300 6850)(-8300 6800);
WIRE 16 -1 (-8300 6800)(-8650 6800);
WIRE 16 -1 (-8650 6850)(-8650 6800);
WIRE 16 -1 (-8650 6800)(-9000 6800);
WIRE 16 -1 (-9000 6850)(-9000 6800);
WIRE 16 -1 (-9000 6800)(-9100 6800);
WIRE 16 -1 (-9500 2425)(-9200 2425);
WIRE 16 -1 (-9500 2525)(-9500 2425);
WIRE 16 -1 (-9500 2525)(-9200 2525);
WIRE 16 -1 (-9500 2600)(-9500 2525);
WIRE 16 -1 (-7250 4475)(-7800 4475);
WIRE 16 -1 (-7800 4400)(-7800 4475);
WIRE 16 -1 (-9800 2300)(-9600 2300);
WIRE 16 -1 (-9800 2400)(-9800 2300);
WIRE 16 -1 (-8800 2000)(-8800 1900);
WIRE 16 -1 (-8800 1900)(-8675 1900);
WIRE 16 -1 (-8675 1900)(-8675 2000);
WIRE 16 -1 (-8675 1850)(-8675 1900);
WIRE 16 -1 (-10850 5875)(-10675 5875);
WIRE 16 -1 (-10850 6125)(-10850 5875);
WIRE 16 -1 (-9425 6125)(-9425 6025);
WIRE 16 -1 (-9425 6025)(-9825 6025);
WIRE 16 -1 (-8725 4175)(-8725 4225);
WIRE 16 -1 (-8725 4225)(-9100 4225);
WIRE 16 -1 (-9100 4250)(-9100 4225);
WIRE 16 -1 (-9100 4225)(-9100 4175);
WIRE 16 -1 (-7250 2325)(-7700 2325);
WIRE 16 -1 (-7700 2250)(-7700 2325);
WIRE 16 -1 (-8050 2000)(-8050 1900);
WIRE 16 -1 (-8050 1900)(-7925 1900);
WIRE 16 -1 (-7925 2000)(-7925 1900);
WIRE 16 -1 (-7925 1900)(-7925 1850);
WIRE 16 -1 (-4475 7950)(-4475 7875);
WIRE 16 -1 (-4475 7875)(-4850 7875);
WIRE 16 -1 (-5900 6425)(-5025 6425);
FORCEPROP 2 LAST SIG_NAME P0V9_RETIMER_CPU0_PWM2
J 0
(-5710 6435);
DISPLAY 0.617021 (-5710 6435);
WIRE 16 -1 (-5900 5425)(-4900 5425);
FORCEPROP 2 LAST SIG_NAME NC_P0V9_RETIMER_CPU0_IMON4
J 0
(-5735 5435);
DISPLAY 0.617021 (-5735 5435);
FORCEPROP 2 LASTPROP $XRERR UNIQUE?
J 0
(-5975 5435);
DISPLAY 0.638298 (-5975 5435);
PAINT MONO (-5975 5435);
DISPLAY INVISIBLE (-5975 5435);
WIRE 16 -1 (-5900 5075)(-5025 5075);
FORCEPROP 2 LAST SIG_NAME NC_P0V9_RETIMER_CPU0_PWM5
J 0
(-5785 5085);
DISPLAY 0.617021 (-5785 5085);
FORCEPROP 2 LASTPROP $XRERR UNIQUE?
J 0
(-5020 5075);
DISPLAY 0.638298 (-5020 5075);
PAINT MONO (-5020 5075);
DISPLAY INVISIBLE (-5020 5075);
WIRE 16 -1 (-5900 4975)(-4875 4975);
FORCEPROP 2 LAST SIG_NAME NC_P0V9_RETIMER_CPU0_IMON5
J 0
(-5785 4985);
DISPLAY 0.617021 (-5785 4985);
FORCEPROP 2 LASTPROP $XRERR UNIQUE?
J 0
(-6025 4985);
DISPLAY 0.638298 (-6025 4985);
PAINT MONO (-6025 4985);
DISPLAY INVISIBLE (-6025 4985);
WIRE 16 -1 (-7250 2775)(-8450 2775);
FORCEPROP 2 LAST SIG_NAME P0V9_RETIMER_CPU0_ADDR
J 0
(-8135 2785);
DISPLAY 0.617021 (-8135 2785);
FORCEPROP 2 LASTPROP $XRERR UNIQUE?
J 0
(-8375 2785);
DISPLAY 0.638298 (-8375 2785);
PAINT MONO (-8375 2785);
DISPLAY INVISIBLE (-8375 2785);
WIRE 16 -1 (-7925 2200)(-7925 2425);
WIRE 16 -1 (-7250 2425)(-7925 2425);
WIRE 16 -1 (-7925 2425)(-8050 2425);
WIRE 16 -1 (-8050 2200)(-8050 2425);
WIRE 16 -1 (-9000 2425)(-8050 2425);
FORCEPROP 2 LAST SIG_NAME P0V9_RETIMER_CPU0_VINSEN
J 0
(-8185 2435);
DISPLAY 0.617021 (-8185 2435);
FORCEPROP 2 LASTPROP $XRERR UNIQUE?
J 0
(-8425 2435);
DISPLAY 0.638298 (-8425 2435);
PAINT MONO (-8425 2435);
DISPLAY INVISIBLE (-8425 2435);
WIRE 16 -1 (-8950 2525)(-8800 2525);
WIRE 16 -1 (-8950 2525)(-8950 2300);
WIRE 16 -1 (-9000 2525)(-8950 2525);
WIRE 16 -1 (-8800 2525)(-8675 2525);
WIRE 16 -1 (-8800 2200)(-8800 2525);
WIRE 16 -1 (-7250 2525)(-8675 2525);
FORCEPROP 2 LAST SIG_NAME P0V9_RETIMER_CPU0_VMON
J 0
(-8135 2535);
DISPLAY 0.617021 (-8135 2535);
FORCEPROP 2 LASTPROP $XRERR UNIQUE?
J 0
(-8375 2535);
DISPLAY 0.638298 (-8375 2535);
PAINT MONO (-8375 2535);
DISPLAY INVISIBLE (-8375 2535);
WIRE 16 -1 (-8675 2200)(-8675 2525);
WIRE 16 -1 (-8950 2300)(-9400 2300);
WIRE 17 273 (-11575 2325)(-10350 2325);
WIRE 17 273 (-11575 2325)(-11575 1900);
WIRE 17 273 (-10350 2325)(-10350 1900);
WIRE 17 273 (-11575 1900)(-10350 1900);
WIRE 16 -1 (-5900 3725)(-5025 3725);
FORCEPROP 2 LAST SIG_NAME NC_P0V9_RETIMER_CPU0_PWM8
J 0
(-5785 3735);
DISPLAY 0.617021 (-5785 3735);
FORCEPROP 2 LASTPROP $XRERR UNIQUE?
J 0
(-5020 3725);
DISPLAY 0.638298 (-5020 3725);
PAINT MONO (-5020 3725);
DISPLAY INVISIBLE (-5020 3725);
WIRE 16 -1 (-5900 6875)(-5025 6875);
FORCEPROP 2 LAST SIG_NAME P0V9_RETIMER_CPU0_PWM1
J 0
(-5735 6885);
DISPLAY 0.617021 (-5735 6885);
WIRE 16 -1 (-9875 7425)(-9475 7425);
WIRE 16 -1 (-9875 7500)(-9875 7425);
WIRE 16 -1 (-9875 7425)(-9875 7275);
WIRE 16 -1 (-9875 7275)(-9475 7275);
WIRE 16 -1 (-9875 7275)(-9875 7125);
WIRE 16 -1 (-9875 7125)(-9475 7125);
WIRE 16 -1 (-9875 6425)(-9875 7125);
WIRE 16 -1 (-9400 6425)(-9875 6425);
WIRE 16 -1 (-7250 7425)(-9000 7425);
FORCEPROP 2 LAST SIG_NAME P0V9_RETIMER_CPU0_SVID_CLK
J 0
(-8485 7435);
DISPLAY 0.808511 (-8485 7435);
FORCEPROP 2 LASTPROP $XRERR UNIQUE?
J 0
(-8725 7435);
DISPLAY 0.638298 (-8725 7435);
PAINT MONO (-8725 7435);
DISPLAY INVISIBLE (-8725 7435);
WIRE 16 -1 (-9000 7050)(-9000 7425);
WIRE 16 -1 (-9000 7425)(-9275 7425);
WIRE 16 -1 (-7250 7125)(-8300 7125);
FORCEPROP 2 LAST SIG_NAME TP_P0V9_RETIMER_CPU0_SVID_ALERT_N
J 0
(-8760 7135);
DISPLAY 0.808511 (-8760 7135);
FORCEPROP 2 LASTPROP $XRERR UNIQUE?
J 0
(-9000 7135);
DISPLAY 0.638298 (-9000 7135);
PAINT MONO (-9000 7135);
DISPLAY INVISIBLE (-9000 7135);
WIRE 16 -1 (-8300 7050)(-8300 7125);
WIRE 16 -1 (-8300 7125)(-9275 7125);
WIRE 16 -1 (-5800 7575)(-5800 7400);
WIRE 16 -1 (-5800 7575)(-5900 7575);
WIRE 16 -1 (-5675 7400)(-5800 7400);
FORCEPROP 2 LAST SIG_NAME PV09_RETIMER_CPU0_VCCS
J 0
(-5710 7410);
DISPLAY 0.617021 (-5710 7410);
WIRE 16 -1 (-5275 7400)(-5675 7400);
WIRE 16 -1 (-5675 7300)(-5675 7400);
WIRE 16 -1 (-4775 7400)(-5275 7400);
WIRE 16 -1 (-5275 7300)(-5275 7400);
WIRE 16 -1 (-5275 7575)(-5275 7475);
WIRE 16 -1 (-4875 7475)(-5275 7475);
WIRE 16 -1 (-5675 7475)(-5275 7475);
WIRE 16 -1 (-5675 7575)(-5675 7475);
WIRE 16 -1 (-5275 7775)(-5275 7875);
WIRE 16 -1 (-5050 7875)(-5275 7875);
WIRE 16 -1 (-5675 7875)(-5275 7875);
WIRE 16 -1 (-5675 7775)(-5675 7875);
WIRE 16 -1 (-5900 7875)(-5675 7875);
FORCEPROP 2 LAST SIG_NAME P0V9_RETIMER_CPU0_VCC
J 0
(-5710 7885);
DISPLAY 0.617021 (-5710 7885);
FORCEPROP 2 LASTPROP $XRERR UNIQUE?
J 0
(-5950 7885);
DISPLAY 0.638298 (-5950 7885);
PAINT MONO (-5950 7885);
DISPLAY INVISIBLE (-5950 7885);
DOT 1 (-10250 5500);
DOT 1 (-8875 7725);
DOT 1 (-8300 7125);
DOT 1 (-8650 7275);
DOT 1 (-9000 6800);
DOT 1 (-9500 2525);
DOT 1 (-8450 5875);
DOT 1 (-9000 7425);
DOT 1 (-8775 7875);
DOT 1 (-9875 7125);
DOT 1 (-8675 1900);
DOT 1 (-7925 1900);
DOT 1 (-9875 7275);
DOT 1 (-5675 7875);
DOT 1 (-9100 4225);
DOT 1 (-5275 7875);
DOT 1 (-5275 7400);
DOT 1 (-4600 2675);
DOT 1 (-8450 5500);
DOT 1 (-9875 7425);
DOT 1 (-8650 6800);
DOT 1 (-8950 2525);
DOT 1 (-8800 2525);
DOT 1 (-5275 7000);
DOT 1 (-8050 2425);
DOT 1 (-7925 2425);
DOT 1 (-5300 2675);
DOT 1 (-5675 7400);
DOT 1 (-8775 8025);
DOT 1 (-9575 7875);
DOT 1 (-10250 5875);
DOT 1 (-8675 2525);
DOT 1 (-5275 7475);
FORCENOTE
MAIN SOURCE: RENESAS    BOM
(-4300 6850) 0;
DISPLAY LEFT (-4300 6850);
DISPLAY 1.021277 (-4300 6850);
PAINT WHITE (-4300 6850);
FORCENOTE
BOM NOTE
(-4300 6950) 0;
DISPLAY LEFT (-4300 6950);
DISPLAY 1.021277 (-4300 6950);
PAINT WHITE (-4300 6950);
FORCENOTE
PU6502 = TBD / ISL69260IRAZ-T
(-4300 6750) 0;
DISPLAY LEFT (-4300 6750);
DISPLAY 1.021277 (-4300 6750);
PAINT WHITE (-4300 6750);
FORCENOTE
DESIGN SPECIFICATION
(-4100 8125) 0;
DISPLAY LEFT (-4100 8125);
DISPLAY 1.276596 (-4100 8125);
PAINT PEACH (-4100 8125);
FORCENOTE
TRANSIENT TOLERANCE = 90MV
(-4050 7875) 0;
DISPLAY LEFT (-4050 7875);
DISPLAY 1.021277 (-4050 7875);
PAINT PEACH (-4050 7875);
FORCENOTE
OUTPUT RIPPLE & NOISE < 46MV
(-4050 7950) 0;
DISPLAY LEFT (-4050 7950);
DISPLAY 1.021277 (-4050 7950);
PAINT PEACH (-4050 7950);
FORCENOTE
OUTPUT VOLTAGE = 0.86V - 0.945V
(-4050 8025) 0;
DISPLAY LEFT (-4050 8025);
DISPLAY 1.021277 (-4050 8025);
PAINT PEACH (-4050 8025);
FORCENOTE
TDC = 54.8A
(-4025 7775) 0;
DISPLAY LEFT (-4025 7775);
DISPLAY 1.021277 (-4025 7775);
PAINT PEACH (-4025 7775);
FORCENOTE
MAX CURRENT = 57.6A
(-4025 7700) 0;
DISPLAY LEFT (-4025 7700);
DISPLAY 1.021277 (-4025 7700);
PAINT PEACH (-4025 7700);
FORCENOTE
OVER-CURRENT PROTECTION= 92A
(-4025 7625) 0;
DISPLAY LEFT (-4025 7625);
DISPLAY 1.021277 (-4025 7625);
PAINT PEACH (-4025 7625);
FORCENOTE
TRACE SPACING = 5MIL
(-11725 5550) 0;
DISPLAY LEFT (-11725 5550);
DISPLAY 1.021277 (-11725 5550);
PAINT PINK (-11725 5550);
FORCENOTE
TRACE WIDTH = 10MIL
(-11725 5625) 0;
DISPLAY LEFT (-11725 5625);
DISPLAY 1.021277 (-11725 5625);
PAINT PINK (-11725 5625);
FORCENOTE
DIFFERENTIAL PAIR
(-11725 5700) 0;
DISPLAY LEFT (-11725 5700);
DISPLAY 1.021277 (-11725 5700);
PAINT PINK (-11725 5700);
FORCENOTE
PC6606 = CH4106K1B01
(-4225 5450) 0;
DISPLAY LEFT (-4225 5450);
DISPLAY 1.021277 (-4225 5450);
PAINT WHITE (-4225 5450);
FORCENOTE
PC6607 = CH11006JB00
(-4225 5550) 0;
DISPLAY LEFT (-4225 5550);
DISPLAY 1.021277 (-4225 5550);
PAINT WHITE (-4225 5550);
FORCENOTE
PC6601 = CH3104J1B00
(-4225 5650) 0;
DISPLAY LEFT (-4225 5650);
DISPLAY 1.021277 (-4225 5650);
PAINT WHITE (-4225 5650);
FORCENOTE
PC6540 = CH12206KB14
(-4225 5750) 0;
DISPLAY LEFT (-4225 5750);
DISPLAY 1.021277 (-4225 5750);
PAINT WHITE (-4225 5750);
FORCENOTE
PR6604 = CS25362FB02
(-4225 5850) 0;
DISPLAY LEFT (-4225 5850);
DISPLAY 1.021277 (-4225 5850);
PAINT WHITE (-4225 5850);
FORCENOTE
PMBUS ADDRESS AND CONFIG
(-11625 2375) 0;
DISPLAY LEFT (-11625 2375);
DISPLAY 1.170213 (-11625 2375);
PAINT WHITE (-11625 2375);
FORCENOTE
SVID:UNUSED
(-8075 7025) 0;
DISPLAY LEFT (-8075 7025);
DISPLAY 1.021277 (-8075 7025);
PAINT PINK (-8075 7025);
FORCENOTE
VR
(-11525 2250) 0;
DISPLAY LEFT (-11525 2250);
DISPLAY 0.808511 (-11525 2250);
PAINT WHITE (-11525 2250);
FORCENOTE
ADDRESS(7-BIT)
(-11300 2250) 0;
DISPLAY LEFT (-11300 2250);
DISPLAY 0.808511 (-11300 2250);
PAINT WHITE (-11300 2250);
FORCENOTE
LOCAL SENSE
(-9675 6275) 0;
DISPLAY LEFT (-9675 6275);
DISPLAY 1.021277 (-9675 6275);
PAINT PINK (-9675 6275);
FORCENOTE
REMOTE SENSE
(-11125 6275) 0;
DISPLAY LEFT (-11125 6275);
DISPLAY 1.021277 (-11125 6275);
PAINT PINK (-11125 6275);
FORCENOTE
EFFICIENCY > 85% @TDC
(-4025 7325) 0;
DISPLAY LEFT (-4025 7325);
DISPLAY 1.021277 (-4025 7325);
PAINT PEACH (-4025 7325);
FORCENOTE
WORK FREQUENCY = 600KHZ
(-4025 7400) 0;
DISPLAY LEFT (-4025 7400);
DISPLAY 1.021277 (-4025 7400);
PAINT PEACH (-4025 7400);
FORCENOTE
SLEW RATE = 2.5A/US
(-4025 7475) 0;
DISPLAY LEFT (-4025 7475);
DISPLAY 1.021277 (-4025 7475);
PAINT PEACH (-4025 7475);
FORCENOTE
CURRENT STEP = 22A
(-4025 7550) 0;
DISPLAY LEFT (-4025 7550);
DISPLAY 1.021277 (-4025 7550);
PAINT PEACH (-4025 7550);
FORCENOTE
UNUSED
(-7650 3400) 0;
DISPLAY LEFT (-7650 3400);
DISPLAY 1.021277 (-7650 3400);
PAINT PINK (-7650 3400);
FORCENOTE
RENESAS
(-11525 2150) 0;
DISPLAY LEFT (-11525 2150);
DISPLAY 0.638298 (-11525 2150);
PAINT WHITE (-11525 2150);
FORCENOTE
INFENEON
(-11525 2075) 0;
DISPLAY LEFT (-11525 2075);
DISPLAY 0.638298 (-11525 2075);
PAINT WHITE (-11525 2075);
FORCENOTE
0/0
(-10725 2150) 0;
DISPLAY LEFT (-10725 2150);
DISPLAY 0.638298 (-10725 2150);
PAINT WHITE (-10725 2150);
FORCENOTE
0X60
(-11075 2150) 0;
DISPLAY LEFT (-11075 2150);
DISPLAY 0.638298 (-11075 2150);
PAINT WHITE (-11075 2150);
FORCENOTE
0X60
(-11075 2075) 0;
DISPLAY LEFT (-11075 2075);
DISPLAY 0.638298 (-11075 2075);
PAINT WHITE (-11075 2075);
FORCENOTE
/17.4K
(-10725 2075) 0;
DISPLAY LEFT (-10725 2075);
DISPLAY 0.638298 (-10725 2075);
PAINT WHITE (-10725 2075);
FORCENOTE
CONFIG/R
(-10725 2250) 0;
DISPLAY LEFT (-10725 2250);
DISPLAY 0.808511 (-10725 2250);
PAINT WHITE (-10725 2250);
FORCENOTE
PR6603 = CS31742FB04
(-4225 5950) 0;
DISPLAY LEFT (-4225 5950);
DISPLAY 1.021277 (-4225 5950);
PAINT WHITE (-4225 5950);
FORCENOTE
PR6531 = CS01002FB07
(-4225 6050) 0;
DISPLAY LEFT (-4225 6050);
DISPLAY 1.021277 (-4225 6050);
PAINT WHITE (-4225 6050);
FORCENOTE
PR6609,PR6610,PR6611,PR6612,PR6613,PR6614 = EMPTY
(-4300 6175) 0;
DISPLAY LEFT (-4300 6175);
DISPLAY 0.808511 (-4300 6175);
PAINT WHITE (-4300 6175);
FORCENOTE
PR6810,PR6819,R6801,PR6618 = EMPTY
(-4300 6275) 0;
DISPLAY LEFT (-4300 6275);
DISPLAY 0.808511 (-4300 6275);
PAINT WHITE (-4300 6275);
FORCENOTE
PR6803,PR6805,PR6817,PR6605 =  CS21002FB06
(-4300 6375) 0;
DISPLAY LEFT (-4300 6375);
DISPLAY 0.808511 (-4300 6375);
PAINT WHITE (-4300 6375);
FORCENOTE
PU6502 = TBD / XDPE15284D-0000
(-4300 6475) 0;
DISPLAY LEFT (-4300 6475);
DISPLAY 1.021277 (-4300 6475);
PAINT WHITE (-4300 6475);
FORCENOTE
2ND SOURCE: INFENEON   BOM
(-4300 6550) 0;
DISPLAY LEFT (-4300 6550);
DISPLAY 1.021277 (-4300 6550);
PAINT WHITE (-4300 6550);
QUIT
